G04 ================== begin FILE IDENTIFICATION RECORD ==================*
G04 Layout Name:  D:/<user>/Wistron_project/16315-1/gbr/16315-1.brd*
G04 Film Name:    TMASK*
G04 File Format:  Gerber RS274X*
G04 File Origin:  Cadence Allegro 16.5-S056*
G04 Origin Date:  Fri Jun 09 15:30:34 2017*
G04 *
G04 Layer:  VIA CLASS/SOLDERMASK_TOP*
G04 Layer:  PIN/SOLDERMASK_TOP*
G04 Layer:  PACKAGE GEOMETRY/SOLDERMASK_TOP*
G04 Layer:  DRAWING FORMAT/LAYER_PCB_STORY*
G04 Layer:  DRAWING FORMAT/LAYER_SOLDER_T*
G04 Layer:  BOARD GEOMETRY/SOLDERMASK_TOP*
G04 *
G04 Offset:    (0.00 0.00)*
G04 Mirror:    No*
G04 Mode:      Positive*
G04 Rotation:  0*
G04 FullContactRelief:  No*
G04 UndefLineWidth:     6.00*
G04 ================== end FILE IDENTIFICATION RECORD ====================*
%FSLAX35Y35*MOIN*%
%IR0*IPPOS*OFA0.00000B0.00000*MIA0B0*SFA1.00000B1.00000*%
%AMMACRO47*
4,1,40,.013,.017,
-.013,.017,
-.013695,.016939,
-.014368,.016759,
-.015,.016464,
-.015571,.016064,
-.016064,.015571,
-.016464,.015,
-.016759,.014368,
-.016939,.013695,
-.017,.013,
-.017,-.013,
-.016939,-.013695,
-.016759,-.014368,
-.016464,-.015,
-.016064,-.015571,
-.015571,-.016064,
-.015,-.016464,
-.014368,-.016759,
-.013695,-.016939,
-.013,-.017,
.013,-.017,
.013695,-.016939,
.014368,-.016759,
.015,-.016464,
.015571,-.016064,
.016064,-.015571,
.016464,-.015,
.016759,-.014368,
.016939,-.013695,
.017,-.013,
.017,.013,
.016939,.013695,
.016759,.014368,
.016464,.015,
.016064,.015571,
.015571,.016064,
.015,.016464,
.014368,.016759,
.013695,.016939,
.013,.017,
0.0*
%
%ADD47MACRO47*%
%AMMACRO16*
4,1,40,.017,-.013,
.017,.013,
.016939,.013695,
.016759,.014368,
.016464,.015,
.016064,.015571,
.015571,.016064,
.015,.016464,
.014368,.016759,
.013695,.016939,
.013,.017,
-.013,.017,
-.013695,.016939,
-.014368,.016759,
-.015,.016464,
-.015571,.016064,
-.016064,.015571,
-.016464,.015,
-.016759,.014368,
-.016939,.013695,
-.017,.013,
-.017,-.013,
-.016939,-.013695,
-.016759,-.014368,
-.016464,-.015,
-.016064,-.015571,
-.015571,-.016064,
-.015,-.016464,
-.014368,-.016759,
-.013695,-.016939,
-.013,-.017,
.013,-.017,
.013695,-.016939,
.014368,-.016759,
.015,-.016464,
.015571,-.016064,
.016064,-.015571,
.016464,-.015,
.016759,-.014368,
.016939,-.013695,
.017,-.013,
0.0*
%
%ADD16MACRO16*%
%ADD98R,.055X.11*%
%ADD105O,.115X.048*%
%ADD11C,.02*%
%ADD84R,.056X.14*%
%ADD62C,.03*%
%ADD104R,.08X.127*%
%ADD78C,.022*%
%ADD102R,.22X.096*%
%ADD55C,.032*%
%AMMACRO52*
4,1,40,-.007,.004,
-.007,-.004,
-.00697,-.004347,
-.006879,-.004684,
-.006732,-.005,
-.006532,-.005286,
-.006286,-.005532,
-.006,-.005732,
-.005684,-.005879,
-.005347,-.00597,
-.005,-.006,
.005,-.006,
.005347,-.00597,
.005684,-.005879,
.006,-.005732,
.006286,-.005532,
.006532,-.005286,
.006732,-.005,
.006879,-.004684,
.00697,-.004347,
.007,-.004,
.007,.004,
.00697,.004347,
.006879,.004684,
.006732,.005,
.006532,.005286,
.006286,.005532,
.006,.005732,
.005684,.005879,
.005347,.00597,
.005,.006,
-.005,.006,
-.005347,.00597,
-.005684,.005879,
-.006,.005732,
-.006286,.005532,
-.006532,.005286,
-.006732,.005,
-.006879,.004684,
-.00697,.004347,
-.007,.004,
0.0*
%
%ADD52MACRO52*%
%ADD100C,.024*%
%ADD91C,.042*%
%ADD57C,.016*%
%ADD49C,.053*%
%ADD17C,.08*%
%ADD13C,.026*%
%ADD95O,.048X.166*%
%ADD42C,.037*%
%ADD96C,.048*%
%ADD92C,.093*%
%ADD66C,.094*%
%ADD18C,.086*%
%AMMACRO77*
4,1,40,.0225,-.007,
.022378,-.008389,
.022018,-.009736,
.021428,-.011,
.020628,-.012142,
.019642,-.013128,
.0185,-.013928,
.017236,-.014518,
.015889,-.014878,
.0145,-.015,
-.0145,-.015,
-.015889,-.014878,
-.017236,-.014518,
-.0185,-.013928,
-.019642,-.013128,
-.020628,-.012142,
-.021428,-.011,
-.022018,-.009736,
-.022378,-.008389,
-.0225,-.007,
-.0225,.007,
-.022378,.008389,
-.022018,.009736,
-.021428,.011,
-.020628,.012142,
-.019642,.013128,
-.0185,.013928,
-.017236,.014518,
-.015889,.014878,
-.0145,.015,
.0145,.015,
.015889,.014878,
.017236,.014518,
.0185,.013928,
.019642,.013128,
.020628,.012142,
.021428,.011,
.022018,.009736,
.022378,.008389,
.0225,.007,
.0225,-.007,
0.0*
%
%ADD77MACRO77*%
%AMMACRO69*
4,1,46,-.00177,-.018,
-.003163,-.017918,
-.00452,-.017595,
-.0058,-.017042,
-.006965,-.016274,
-.007979,-.015316,
-.008812,-.014196,
-.009437,-.012949,
-.009836,-.011613,
-.009997,-.010227,
-.01,-.01,
-.01,.01,
-.00999,.01,
-.009868,.011389,
-.009507,.012737,
-.008918,.014001,
-.008118,.015143,
-.007132,.016129,
-.005989,.016929,
-.004725,.017519,
-.003378,.01788,
-.001989,.018001,
-.00185,.018,
.00185,.018,
.003241,.017903,
.004595,.017565,
.005869,.016998,
.007025,.016218,
.008028,.015249,
.008848,.01412,
.009459,.012867,
.009843,.011526,
.009989,.010139,
.00999,.01,
.01,.01,
.01,-.01,
.009878,-.01139,
.009517,-.012737,
.008928,-.014002,
.008128,-.015144,
.007141,-.016131,
.005998,-.016931,
.004734,-.017521,
.003387,-.017882,
.001997,-.018003,
.00177,-.018,
-.00177,-.018,
0.0*
%
%ADD69MACRO69*%
%ADD40C,.087*%
%ADD67C,.097*%
%ADD63C,.02617*%
%AMMACRO12*
4,1,40,-.007,-.0225,
-.008389,-.022378,
-.009736,-.022018,
-.011,-.021428,
-.012142,-.020628,
-.013128,-.019642,
-.013928,-.0185,
-.014518,-.017236,
-.014878,-.015889,
-.015,-.0145,
-.015,.0145,
-.014878,.015889,
-.014518,.017236,
-.013928,.0185,
-.013128,.019642,
-.012142,.020628,
-.011,.021428,
-.009736,.022018,
-.008389,.022378,
-.007,.0225,
.007,.0225,
.008389,.022378,
.009736,.022018,
.011,.021428,
.012142,.020628,
.013128,.019642,
.013928,.0185,
.014518,.017236,
.014878,.015889,
.015,.0145,
.015,-.0145,
.014878,-.015889,
.014518,-.017236,
.013928,-.0185,
.013128,-.019642,
.012142,-.020628,
.011,-.021428,
.009736,-.022018,
.008389,-.022378,
.007,-.0225,
-.007,-.0225,
0.0*
%
%ADD12MACRO12*%
%AMMACRO25*
4,1,40,.007,.011,
-.007,.011,
-.007695,.010939,
-.008368,.010759,
-.009,.010464,
-.009571,.010064,
-.010064,.009571,
-.010464,.009,
-.010759,.008368,
-.010939,.007695,
-.011,.007,
-.011,-.007,
-.010939,-.007695,
-.010759,-.008368,
-.010464,-.009,
-.010064,-.009571,
-.009571,-.010064,
-.009,-.010464,
-.008368,-.010759,
-.007695,-.010939,
-.007,-.011,
.007,-.011,
.007695,-.010939,
.008368,-.010759,
.009,-.010464,
.009571,-.010064,
.010064,-.009571,
.010464,-.009,
.010759,-.008368,
.010939,-.007695,
.011,-.007,
.011,.007,
.010939,.007695,
.010759,.008368,
.010464,.009,
.010064,.009571,
.009571,.010064,
.009,.010464,
.008368,.010759,
.007695,.010939,
.007,.011,
0.0*
%
%ADD25MACRO25*%
%AMMACRO19*
4,1,40,.011,-.007,
.011,.007,
.010939,.007695,
.010759,.008368,
.010464,.009,
.010064,.009571,
.009571,.010064,
.009,.010464,
.008368,.010759,
.007695,.010939,
.007,.011,
-.007,.011,
-.007695,.010939,
-.008368,.010759,
-.009,.010464,
-.009571,.010064,
-.010064,.009571,
-.010464,.009,
-.010759,.008368,
-.010939,.007695,
-.011,.007,
-.011,-.007,
-.010939,-.007695,
-.010759,-.008368,
-.010464,-.009,
-.010064,-.009571,
-.009571,-.010064,
-.009,-.010464,
-.008368,-.010759,
-.007695,-.010939,
-.007,-.011,
.007,-.011,
.007695,-.010939,
.008368,-.010759,
.009,-.010464,
.009571,-.010064,
.010064,-.009571,
.010464,-.009,
.010759,-.008368,
.010939,-.007695,
.011,-.007,
0.0*
%
%ADD19MACRO19*%
%AMMACRO33*
4,1,40,-.012,.008,
-.012,-.008,
-.011939,-.008695,
-.011759,-.009368,
-.011464,-.01,
-.011064,-.010571,
-.010571,-.011064,
-.01,-.011464,
-.009368,-.011759,
-.008695,-.011939,
-.008,-.012,
.008,-.012,
.008695,-.011939,
.009368,-.011759,
.01,-.011464,
.010571,-.011064,
.011064,-.010571,
.011464,-.01,
.011759,-.009368,
.011939,-.008695,
.012,-.008,
.012,.008,
.011939,.008695,
.011759,.009368,
.011464,.01,
.011064,.010571,
.010571,.011064,
.01,.011464,
.009368,.011759,
.008695,.011939,
.008,.012,
-.008,.012,
-.008695,.011939,
-.009368,.011759,
-.01,.011464,
-.010571,.011064,
-.011064,.010571,
-.011464,.01,
-.011759,.009368,
-.011939,.008695,
-.012,.008,
0.0*
%
%ADD33MACRO33*%
%AMMACRO60*
4,1,40,.008,.012,
-.008,.012,
-.008695,.011939,
-.009368,.011759,
-.01,.011464,
-.010571,.011064,
-.011064,.010571,
-.011464,.01,
-.011759,.009368,
-.011939,.008695,
-.012,.008,
-.012,-.008,
-.011939,-.008695,
-.011759,-.009368,
-.011464,-.01,
-.011064,-.010571,
-.010571,-.011064,
-.01,-.011464,
-.009368,-.011759,
-.008695,-.011939,
-.008,-.012,
.008,-.012,
.008695,-.011939,
.009368,-.011759,
.01,-.011464,
.010571,-.011064,
.011064,-.010571,
.011464,-.01,
.011759,-.009368,
.011939,-.008695,
.012,-.008,
.012,.008,
.011939,.008695,
.011759,.009368,
.011464,.01,
.011064,.010571,
.010571,.011064,
.01,.011464,
.009368,.011759,
.008695,.011939,
.008,.012,
0.0*
%
%ADD60MACRO60*%
%AMMACRO54*
4,1,40,-.013,-.017,
.013,-.017,
.013695,-.016939,
.014368,-.016759,
.015,-.016464,
.015571,-.016064,
.016064,-.015571,
.016464,-.015,
.016759,-.014368,
.016939,-.013695,
.017,-.013,
.017,.013,
.016939,.013695,
.016759,.014368,
.016464,.015,
.016064,.015571,
.015571,.016064,
.015,.016464,
.014368,.016759,
.013695,.016939,
.013,.017,
-.013,.017,
-.013695,.016939,
-.014368,.016759,
-.015,.016464,
-.015571,.016064,
-.016064,.015571,
-.016464,.015,
-.016759,.014368,
-.016939,.013695,
-.017,.013,
-.017,-.013,
-.016939,-.013695,
-.016759,-.014368,
-.016464,-.015,
-.016064,-.015571,
-.015571,-.016064,
-.015,-.016464,
-.014368,-.016759,
-.013695,-.016939,
-.013,-.017,
0.0*
%
%ADD54MACRO54*%
%AMMACRO37*
4,1,40,-.017,.013,
-.017,-.013,
-.016939,-.013695,
-.016759,-.014368,
-.016464,-.015,
-.016064,-.015571,
-.015571,-.016064,
-.015,-.016464,
-.014368,-.016759,
-.013695,-.016939,
-.013,-.017,
.013,-.017,
.013695,-.016939,
.014368,-.016759,
.015,-.016464,
.015571,-.016064,
.016064,-.015571,
.016464,-.015,
.016759,-.014368,
.016939,-.013695,
.017,-.013,
.017,.013,
.016939,.013695,
.016759,.014368,
.016464,.015,
.016064,.015571,
.015571,.016064,
.015,.016464,
.014368,.016759,
.013695,.016939,
.013,.017,
-.013,.017,
-.013695,.016939,
-.014368,.016759,
-.015,.016464,
-.015571,.016064,
-.016064,.015571,
-.016464,.015,
-.016759,.014368,
-.016939,.013695,
-.017,.013,
0.0*
%
%ADD37MACRO37*%
%AMMACRO26*
4,1,40,.007,.011,
-.007,.011,
-.007695,.010939,
-.008368,.010759,
-.009,.010464,
-.009571,.010064,
-.010064,.009571,
-.010464,.009,
-.010759,.008368,
-.010939,.007695,
-.011,.007,
-.011,-.007,
-.010939,-.007695,
-.010759,-.008368,
-.010464,-.009,
-.010064,-.009571,
-.009571,-.010064,
-.009,-.010464,
-.008368,-.010759,
-.007695,-.010939,
-.007,-.011,
.007,-.011,
.007695,-.010939,
.008368,-.010759,
.009,-.010464,
.009571,-.010064,
.010064,-.009571,
.010464,-.009,
.010759,-.008368,
.010939,-.007695,
.011,-.007,
.011,.007,
.010939,.007695,
.010759,.008368,
.010464,.009,
.010064,.009571,
.009571,.010064,
.009,.010464,
.008368,.010759,
.007695,.010939,
.007,.011,
0.0*
%
%ADD26MACRO26*%
%AMMACRO20*
4,1,40,.011,-.007,
.011,.007,
.010939,.007695,
.010759,.008368,
.010464,.009,
.010064,.009571,
.009571,.010064,
.009,.010464,
.008368,.010759,
.007695,.010939,
.007,.011,
-.007,.011,
-.007695,.010939,
-.008368,.010759,
-.009,.010464,
-.009571,.010064,
-.010064,.009571,
-.010464,.009,
-.010759,.008368,
-.010939,.007695,
-.011,.007,
-.011,-.007,
-.010939,-.007695,
-.010759,-.008368,
-.010464,-.009,
-.010064,-.009571,
-.009571,-.010064,
-.009,-.010464,
-.008368,-.010759,
-.007695,-.010939,
-.007,-.011,
.007,-.011,
.007695,-.010939,
.008368,-.010759,
.009,-.010464,
.009571,-.010064,
.010064,-.009571,
.010464,-.009,
.010759,-.008368,
.010939,-.007695,
.011,-.007,
0.0*
%
%ADD20MACRO20*%
%AMMACRO34*
4,1,40,-.012,.008,
-.012,-.008,
-.011939,-.008695,
-.011759,-.009368,
-.011464,-.01,
-.011064,-.010571,
-.010571,-.011064,
-.01,-.011464,
-.009368,-.011759,
-.008695,-.011939,
-.008,-.012,
.008,-.012,
.008695,-.011939,
.009368,-.011759,
.01,-.011464,
.010571,-.011064,
.011064,-.010571,
.011464,-.01,
.011759,-.009368,
.011939,-.008695,
.012,-.008,
.012,.008,
.011939,.008695,
.011759,.009368,
.011464,.01,
.011064,.010571,
.010571,.011064,
.01,.011464,
.009368,.011759,
.008695,.011939,
.008,.012,
-.008,.012,
-.008695,.011939,
-.009368,.011759,
-.01,.011464,
-.010571,.011064,
-.011064,.010571,
-.011464,.01,
-.011759,.009368,
-.011939,.008695,
-.012,.008,
0.0*
%
%ADD34MACRO34*%
%AMMACRO61*
4,1,40,.008,.012,
-.008,.012,
-.008695,.011939,
-.009368,.011759,
-.01,.011464,
-.010571,.011064,
-.011064,.010571,
-.011464,.01,
-.011759,.009368,
-.011939,.008695,
-.012,.008,
-.012,-.008,
-.011939,-.008695,
-.011759,-.009368,
-.011464,-.01,
-.011064,-.010571,
-.010571,-.011064,
-.01,-.011464,
-.009368,-.011759,
-.008695,-.011939,
-.008,-.012,
.008,-.012,
.008695,-.011939,
.009368,-.011759,
.01,-.011464,
.010571,-.011064,
.011064,-.010571,
.011464,-.01,
.011759,-.009368,
.011939,-.008695,
.012,-.008,
.012,.008,
.011939,.008695,
.011759,.009368,
.011464,.01,
.011064,.010571,
.010571,.011064,
.01,.011464,
.009368,.011759,
.008695,.011939,
.008,.012,
0.0*
%
%ADD61MACRO61*%
%AMMACRO53*
4,1,40,-.013,-.017,
.013,-.017,
.013695,-.016939,
.014368,-.016759,
.015,-.016464,
.015571,-.016064,
.016064,-.015571,
.016464,-.015,
.016759,-.014368,
.016939,-.013695,
.017,-.013,
.017,.013,
.016939,.013695,
.016759,.014368,
.016464,.015,
.016064,.015571,
.015571,.016064,
.015,.016464,
.014368,.016759,
.013695,.016939,
.013,.017,
-.013,.017,
-.013695,.016939,
-.014368,.016759,
-.015,.016464,
-.015571,.016064,
-.016064,.015571,
-.016464,.015,
-.016759,.014368,
-.016939,.013695,
-.017,.013,
-.017,-.013,
-.016939,-.013695,
-.016759,-.014368,
-.016464,-.015,
-.016064,-.015571,
-.015571,-.016064,
-.015,-.016464,
-.014368,-.016759,
-.013695,-.016939,
-.013,-.017,
0.0*
%
%ADD53MACRO53*%
%AMMACRO38*
4,1,40,-.017,.013,
-.017,-.013,
-.016939,-.013695,
-.016759,-.014368,
-.016464,-.015,
-.016064,-.015571,
-.015571,-.016064,
-.015,-.016464,
-.014368,-.016759,
-.013695,-.016939,
-.013,-.017,
.013,-.017,
.013695,-.016939,
.014368,-.016759,
.015,-.016464,
.015571,-.016064,
.016064,-.015571,
.016464,-.015,
.016759,-.014368,
.016939,-.013695,
.017,-.013,
.017,.013,
.016939,.013695,
.016759,.014368,
.016464,.015,
.016064,.015571,
.015571,.016064,
.015,.016464,
.014368,.016759,
.013695,.016939,
.013,.017,
-.013,.017,
-.013695,.016939,
-.014368,.016759,
-.015,.016464,
-.015571,.016064,
-.016064,.015571,
-.016464,.015,
-.016759,.014368,
-.016939,.013695,
-.017,.013,
0.0*
%
%ADD38MACRO38*%
%ADD65R,.04X.022*%
%ADD99R,.02X.06*%
%ADD79R,.06X.03*%
%ADD27R,.022X.04*%
%ADD106R,.012X.06*%
%ADD101R,.03X.06*%
%ADD75R,.012X.042*%
%ADD73R,.042X.012*%
%ADD89R,.06X.014*%
%ADD64R,.04X.016*%
%ADD80R,.045X.03*%
%ADD59R,.014X.06*%
%ADD56C,.111*%
%ADD45R,.016X.04*%
%ADD109R,.03X.045*%
%ADD74R,.012X.036*%
%ADD72R,.036X.012*%
%AMMACRO107*
4,1,40,.007,-.004,
.007,.004,
.00697,.004347,
.006879,.004684,
.006732,.005,
.006532,.005286,
.006286,.005532,
.006,.005732,
.005684,.005879,
.005347,.00597,
.005,.006,
-.005,.006,
-.005347,.00597,
-.005684,.005879,
-.006,.005732,
-.006286,.005532,
-.006532,.005286,
-.006732,.005,
-.006879,.004684,
-.00697,.004347,
-.007,.004,
-.007,-.004,
-.00697,-.004347,
-.006879,-.004684,
-.006732,-.005,
-.006532,-.005286,
-.006286,-.005532,
-.006,-.005732,
-.005684,-.005879,
-.005347,-.00597,
-.005,-.006,
.005,-.006,
.005347,-.00597,
.005684,-.005879,
.006,-.005732,
.006286,-.005532,
.006532,-.005286,
.006732,-.005,
.006879,-.004684,
.00697,-.004347,
.007,-.004,
0.0*
%
%ADD107MACRO107*%
%ADD88R,.016X.06*%
%ADD43R,.093X.02*%
%ADD97R,.02X.093*%
%ADD30R,.05X.065*%
%ADD68C,.404*%
%ADD46R,.065X.05*%
%ADD108R,.065X.025*%
%ADD81R,.045X.09*%
%ADD44R,.093X.024*%
%ADD35R,.028X.034*%
%ADD110R,.09X.045*%
%ADD93R,.024X.093*%
%ADD58R,.048X.016*%
%ADD41R,.102X.102*%
%ADD32R,.025X.065*%
%ADD31R,.045X.055*%
%ADD94R,.016X.048*%
%ADD76R,.13X.13*%
%ADD50R,.055X.045*%
%ADD86R,.047X.073*%
%ADD83R,.024X.059*%
%ADD87R,.073X.047*%
%ADD14C,.256*%
%AMMACRO112*
4,1,46,.00177,.018,
.003163,.017918,
.00452,.017595,
.0058,.017042,
.006965,.016274,
.007979,.015316,
.008812,.014196,
.009437,.012949,
.009836,.011613,
.009997,.010227,
.01,.01,
.01,-.01,
.00999,-.01,
.009868,-.011389,
.009507,-.012737,
.008918,-.014001,
.008118,-.015143,
.007132,-.016129,
.005989,-.016929,
.004725,-.017519,
.003378,-.01788,
.001989,-.018001,
.00185,-.018,
-.00185,-.018,
-.003241,-.017903,
-.004595,-.017565,
-.005869,-.016998,
-.007025,-.016218,
-.008028,-.015249,
-.008848,-.01412,
-.009459,-.012867,
-.009843,-.011526,
-.009989,-.010139,
-.00999,-.01,
-.01,-.01,
-.01,.01,
-.009878,.01139,
-.009517,.012737,
-.008928,.014002,
-.008128,.015144,
-.007141,.016131,
-.005998,.016931,
-.004734,.017521,
-.003387,.017882,
-.001997,.018003,
-.00177,.018,
.00177,.018,
0.0*
%
%ADD112MACRO112*%
%ADD103R,.035X.096*%
%ADD85R,.09X.095*%
%AMMACRO111*
4,1,40,-.0225,.007,
-.022378,.008389,
-.022018,.009736,
-.021428,.011,
-.020628,.012142,
-.019642,.013128,
-.0185,.013928,
-.017236,.014518,
-.015889,.014878,
-.0145,.015,
.0145,.015,
.015889,.014878,
.017236,.014518,
.0185,.013928,
.019642,.013128,
.020628,.012142,
.021428,.011,
.022018,.009736,
.022378,.008389,
.0225,.007,
.0225,-.007,
.022378,-.008389,
.022018,-.009736,
.021428,-.011,
.020628,-.012142,
.019642,-.013128,
.0185,-.013928,
.017236,-.014518,
.015889,-.014878,
.0145,-.015,
-.0145,-.015,
-.015889,-.014878,
-.017236,-.014518,
-.0185,-.013928,
-.019642,-.013128,
-.020628,-.012142,
-.021428,-.011,
-.022018,-.009736,
-.022378,-.008389,
-.0225,-.007,
-.0225,.007,
0.0*
%
%ADD111MACRO111*%
%ADD39C,.375*%
%AMMACRO36*
4,1,40,.007,.0225,
.008389,.022378,
.009736,.022018,
.011,.021428,
.012142,.020628,
.013128,.019642,
.013928,.0185,
.014518,.017236,
.014878,.015889,
.015,.0145,
.015,-.0145,
.014878,-.015889,
.014518,-.017236,
.013928,-.0185,
.013128,-.019642,
.012142,-.020628,
.011,-.021428,
.009736,-.022018,
.008389,-.022378,
.007,-.0225,
-.007,-.0225,
-.008389,-.022378,
-.009736,-.022018,
-.011,-.021428,
-.012142,-.020628,
-.013128,-.019642,
-.013928,-.0185,
-.014518,-.017236,
-.014878,-.015889,
-.015,-.0145,
-.015,.0145,
-.014878,.015889,
-.014518,.017236,
-.013928,.0185,
-.013128,.019642,
-.012142,.020628,
-.011,.021428,
-.009736,.022018,
-.008389,.022378,
-.007,.0225,
.007,.0225,
0.0*
%
%ADD36MACRO36*%
%ADD10C,.296*%
%ADD51O,.552X.788*%
%ADD82R,.059X.079*%
%AMMACRO71*
4,1,40,-.008,-.012,
.008,-.012,
.008695,-.011939,
.009368,-.011759,
.01,-.011464,
.010571,-.011064,
.011064,-.010571,
.011464,-.01,
.011759,-.009368,
.011939,-.008695,
.012,-.008,
.012,.008,
.011939,.008695,
.011759,.009368,
.011464,.01,
.011064,.010571,
.010571,.011064,
.01,.011464,
.009368,.011759,
.008695,.011939,
.008,.012,
-.008,.012,
-.008695,.011939,
-.009368,.011759,
-.01,.011464,
-.010571,.011064,
-.011064,.010571,
-.011464,.01,
-.011759,.009368,
-.011939,.008695,
-.012,.008,
-.012,-.008,
-.011939,-.008695,
-.011759,-.009368,
-.011464,-.01,
-.011064,-.010571,
-.010571,-.011064,
-.01,-.011464,
-.009368,-.011759,
-.008695,-.011939,
-.008,-.012,
0.0*
%
%ADD71MACRO71*%
%AMMACRO28*
4,1,40,.012,-.008,
.012,.008,
.011939,.008695,
.011759,.009368,
.011464,.01,
.011064,.010571,
.010571,.011064,
.01,.011464,
.009368,.011759,
.008695,.011939,
.008,.012,
-.008,.012,
-.008695,.011939,
-.009368,.011759,
-.01,.011464,
-.010571,.011064,
-.011064,.010571,
-.011464,.01,
-.011759,.009368,
-.011939,.008695,
-.012,.008,
-.012,-.008,
-.011939,-.008695,
-.011759,-.009368,
-.011464,-.01,
-.011064,-.010571,
-.010571,-.011064,
-.01,-.011464,
-.009368,-.011759,
-.008695,-.011939,
-.008,-.012,
.008,-.012,
.008695,-.011939,
.009368,-.011759,
.01,-.011464,
.010571,-.011064,
.011064,-.010571,
.011464,-.01,
.011759,-.009368,
.011939,-.008695,
.012,-.008,
0.0*
%
%ADD28MACRO28*%
%AMMACRO23*
4,1,40,-.007,-.011,
.007,-.011,
.007695,-.010939,
.008368,-.010759,
.009,-.010464,
.009571,-.010064,
.010064,-.009571,
.010464,-.009,
.010759,-.008368,
.010939,-.007695,
.011,-.007,
.011,.007,
.010939,.007695,
.010759,.008368,
.010464,.009,
.010064,.009571,
.009571,.010064,
.009,.010464,
.008368,.010759,
.007695,.010939,
.007,.011,
-.007,.011,
-.007695,.010939,
-.008368,.010759,
-.009,.010464,
-.009571,.010064,
-.010064,.009571,
-.010464,.009,
-.010759,.008368,
-.010939,.007695,
-.011,.007,
-.011,-.007,
-.010939,-.007695,
-.010759,-.008368,
-.010464,-.009,
-.010064,-.009571,
-.009571,-.010064,
-.009,-.010464,
-.008368,-.010759,
-.007695,-.010939,
-.007,-.011,
0.0*
%
%ADD23MACRO23*%
%AMMACRO21*
4,1,40,-.011,.007,
-.011,-.007,
-.010939,-.007695,
-.010759,-.008368,
-.010464,-.009,
-.010064,-.009571,
-.009571,-.010064,
-.009,-.010464,
-.008368,-.010759,
-.007695,-.010939,
-.007,-.011,
.007,-.011,
.007695,-.010939,
.008368,-.010759,
.009,-.010464,
.009571,-.010064,
.010064,-.009571,
.010464,-.009,
.010759,-.008368,
.010939,-.007695,
.011,-.007,
.011,.007,
.010939,.007695,
.010759,.008368,
.010464,.009,
.010064,.009571,
.009571,.010064,
.009,.010464,
.008368,.010759,
.007695,.010939,
.007,.011,
-.007,.011,
-.007695,.010939,
-.008368,.010759,
-.009,.010464,
-.009571,.010064,
-.010064,.009571,
-.010464,.009,
-.010759,.008368,
-.010939,.007695,
-.011,.007,
0.0*
%
%ADD21MACRO21*%
%AMMACRO90*
4,1,45,.25591,.11811,
.25591,-.11811,
.252022,-.162547,
.240477,-.205635,
.221625,-.246062,
.19604,-.282603,
.164498,-.314145,
.127958,-.33973,
.08753,-.358582,
.044442,-.370127,
.000005,-.374015,
-.044432,-.370127,
-.08752,-.358582,
-.127947,-.33973,
-.164488,-.314145,
-.19603,-.282603,
-.221615,-.246063,
-.240467,-.205635,
-.252012,-.162547,
-.2559,-.11811,
-.2559,.11811,
-.252012,.162547,
-.240467,.205634,
-.221616,.246061,
-.19603,.282601,
-.164488,.314143,
-.127949,.339728,
-.087521,.35858,
-.044434,.370125,
.000003,.374013,
.04444,.370125,
.087526,.35858,
.127954,.339728,
.16179,.31638,
.165832,.290964,
.174225,.266637,
.186715,.244136,
.202923,.224146,
.222356,.207275,
.24439,.19405,
.248391,.17971,
.251551,.165162,
.25386,.150455,
.25531,.135639,
.255896,.120763,
.25591,.11811,
0.0*
%
%ADD90MACRO90*%
%AMMACRO48*
4,1,40,.013,.017,
-.013,.017,
-.013695,.016939,
-.014368,.016759,
-.015,.016464,
-.015571,.016064,
-.016064,.015571,
-.016464,.015,
-.016759,.014368,
-.016939,.013695,
-.017,.013,
-.017,-.013,
-.016939,-.013695,
-.016759,-.014368,
-.016464,-.015,
-.016064,-.015571,
-.015571,-.016064,
-.015,-.016464,
-.014368,-.016759,
-.013695,-.016939,
-.013,-.017,
.013,-.017,
.013695,-.016939,
.014368,-.016759,
.015,-.016464,
.015571,-.016064,
.016064,-.015571,
.016464,-.015,
.016759,-.014368,
.016939,-.013695,
.017,-.013,
.017,.013,
.016939,.013695,
.016759,.014368,
.016464,.015,
.016064,.015571,
.015571,.016064,
.015,.016464,
.014368,.016759,
.013695,.016939,
.013,.017,
0.0*
%
%ADD48MACRO48*%
%AMMACRO15*
4,1,40,.017,-.013,
.017,.013,
.016939,.013695,
.016759,.014368,
.016464,.015,
.016064,.015571,
.015571,.016064,
.015,.016464,
.014368,.016759,
.013695,.016939,
.013,.017,
-.013,.017,
-.013695,.016939,
-.014368,.016759,
-.015,.016464,
-.015571,.016064,
-.016064,.015571,
-.016464,.015,
-.016759,.014368,
-.016939,.013695,
-.017,.013,
-.017,-.013,
-.016939,-.013695,
-.016759,-.014368,
-.016464,-.015,
-.016064,-.015571,
-.015571,-.016064,
-.015,-.016464,
-.014368,-.016759,
-.013695,-.016939,
-.013,-.017,
.013,-.017,
.013695,-.016939,
.014368,-.016759,
.015,-.016464,
.015571,-.016064,
.016064,-.015571,
.016464,-.015,
.016759,-.014368,
.016939,-.013695,
.017,-.013,
0.0*
%
%ADD15MACRO15*%
%AMMACRO70*
4,1,40,-.008,-.012,
.008,-.012,
.008695,-.011939,
.009368,-.011759,
.01,-.011464,
.010571,-.011064,
.011064,-.010571,
.011464,-.01,
.011759,-.009368,
.011939,-.008695,
.012,-.008,
.012,.008,
.011939,.008695,
.011759,.009368,
.011464,.01,
.011064,.010571,
.010571,.011064,
.01,.011464,
.009368,.011759,
.008695,.011939,
.008,.012,
-.008,.012,
-.008695,.011939,
-.009368,.011759,
-.01,.011464,
-.010571,.011064,
-.011064,.010571,
-.011464,.01,
-.011759,.009368,
-.011939,.008695,
-.012,.008,
-.012,-.008,
-.011939,-.008695,
-.011759,-.009368,
-.011464,-.01,
-.011064,-.010571,
-.010571,-.011064,
-.01,-.011464,
-.009368,-.011759,
-.008695,-.011939,
-.008,-.012,
0.0*
%
%ADD70MACRO70*%
%AMMACRO29*
4,1,40,.012,-.008,
.012,.008,
.011939,.008695,
.011759,.009368,
.011464,.01,
.011064,.010571,
.010571,.011064,
.01,.011464,
.009368,.011759,
.008695,.011939,
.008,.012,
-.008,.012,
-.008695,.011939,
-.009368,.011759,
-.01,.011464,
-.010571,.011064,
-.011064,.010571,
-.011464,.01,
-.011759,.009368,
-.011939,.008695,
-.012,.008,
-.012,-.008,
-.011939,-.008695,
-.011759,-.009368,
-.011464,-.01,
-.011064,-.010571,
-.010571,-.011064,
-.01,-.011464,
-.009368,-.011759,
-.008695,-.011939,
-.008,-.012,
.008,-.012,
.008695,-.011939,
.009368,-.011759,
.01,-.011464,
.010571,-.011064,
.011064,-.010571,
.011464,-.01,
.011759,-.009368,
.011939,-.008695,
.012,-.008,
0.0*
%
%ADD29MACRO29*%
%AMMACRO24*
4,1,40,-.007,-.011,
.007,-.011,
.007695,-.010939,
.008368,-.010759,
.009,-.010464,
.009571,-.010064,
.010064,-.009571,
.010464,-.009,
.010759,-.008368,
.010939,-.007695,
.011,-.007,
.011,.007,
.010939,.007695,
.010759,.008368,
.010464,.009,
.010064,.009571,
.009571,.010064,
.009,.010464,
.008368,.010759,
.007695,.010939,
.007,.011,
-.007,.011,
-.007695,.010939,
-.008368,.010759,
-.009,.010464,
-.009571,.010064,
-.010064,.009571,
-.010464,.009,
-.010759,.008368,
-.010939,.007695,
-.011,.007,
-.011,-.007,
-.010939,-.007695,
-.010759,-.008368,
-.010464,-.009,
-.010064,-.009571,
-.009571,-.010064,
-.009,-.010464,
-.008368,-.010759,
-.007695,-.010939,
-.007,-.011,
0.0*
%
%ADD24MACRO24*%
%AMMACRO22*
4,1,40,-.011,.007,
-.011,-.007,
-.010939,-.007695,
-.010759,-.008368,
-.010464,-.009,
-.010064,-.009571,
-.009571,-.010064,
-.009,-.010464,
-.008368,-.010759,
-.007695,-.010939,
-.007,-.011,
.007,-.011,
.007695,-.010939,
.008368,-.010759,
.009,-.010464,
.009571,-.010064,
.010064,-.009571,
.010464,-.009,
.010759,-.008368,
.010939,-.007695,
.011,-.007,
.011,.007,
.010939,.007695,
.010759,.008368,
.010464,.009,
.010064,.009571,
.009571,.010064,
.009,.010464,
.008368,.010759,
.007695,.010939,
.007,.011,
-.007,.011,
-.007695,.010939,
-.008368,.010759,
-.009,.010464,
-.009571,.010064,
-.010064,.009571,
-.010464,.009,
-.010759,.008368,
-.010939,.007695,
-.011,.007,
0.0*
%
%ADD22MACRO22*%
%ADD113C,.006*%
G75*
%LPD*%
G75*
G36*
G01X653392Y585286D02*
X661992D01*
Y594286D01*
X653392D01*
Y585286D01*
G37*
G36*
G01Y606086D02*
X661992D01*
Y597086D01*
X653392D01*
Y606086D01*
G37*
G36*
G01X664792Y597086D02*
X673392D01*
Y606086D01*
X664792D01*
Y597086D01*
G37*
G36*
G01X673392Y585286D02*
X664792D01*
Y594286D01*
X673392D01*
Y585286D01*
G37*
G36*
G01X1047955Y1487511D02*
Y1496111D01*
X1038955D01*
Y1487511D01*
X1047955D01*
G37*
G36*
G01X1027155D02*
Y1496111D01*
X1036155D01*
Y1487511D01*
X1027155D01*
G37*
G36*
G01X1036155Y1498911D02*
Y1507511D01*
X1027155D01*
Y1498911D01*
X1036155D01*
G37*
G36*
G01X1047955Y1507511D02*
Y1498911D01*
X1038955D01*
Y1507511D01*
X1047955D01*
G37*
G36*
G01X1020155Y1487511D02*
Y1496111D01*
X1011155D01*
Y1487511D01*
X1020155D01*
G37*
G36*
G01X999355D02*
Y1496111D01*
X1008355D01*
Y1487511D01*
X999355D01*
G37*
G36*
G01X1008355Y1498911D02*
Y1507511D01*
X999355D01*
Y1498911D01*
X1008355D01*
G37*
G36*
G01X1020155Y1507511D02*
Y1498911D01*
X1011155D01*
Y1507511D01*
X1020155D01*
G37*
G36*
G01X1075755Y1487511D02*
Y1496111D01*
X1066755D01*
Y1487511D01*
X1075755D01*
G37*
G36*
G01X1054955D02*
Y1496111D01*
X1063955D01*
Y1487511D01*
X1054955D01*
G37*
G36*
G01X1063955Y1498911D02*
Y1507511D01*
X1054955D01*
Y1498911D01*
X1063955D01*
G37*
G36*
G01X1075755Y1507511D02*
Y1498911D01*
X1066755D01*
Y1507511D01*
X1075755D01*
G37*
G36*
G01X1373300Y545900D02*
Y554500D01*
X1382300D01*
Y545900D01*
X1373300D01*
G37*
G36*
G01X1382300Y557300D02*
Y565900D01*
X1373300D01*
Y557300D01*
X1382300D01*
G37*
G36*
G01X1394100Y545900D02*
Y554500D01*
X1385100D01*
Y545900D01*
X1394100D01*
G37*
G36*
G01Y565900D02*
Y557300D01*
X1385100D01*
Y565900D01*
X1394100D01*
G37*
G54D100*
X1039845Y1467746D03*
X1026345D03*
X1030845D03*
X1035345D03*
X1039845Y1463246D03*
X1026345D03*
X1030845D03*
X1035345D03*
X1005400Y1463157D03*
X1000900D03*
X996400D03*
X1009900D03*
X1005400Y1467657D03*
X1000900D03*
X996400D03*
X1009900D03*
X1035345Y1476746D03*
X1030845D03*
X1026345D03*
X1039845D03*
Y1472246D03*
X1026345D03*
X1030845D03*
X1035345D03*
X1005400Y1472157D03*
X1000900D03*
X996400D03*
X1009900D03*
Y1476657D03*
X1005400D03*
X1000900D03*
X996400D03*
X1023583Y1489593D03*
X995783D03*
X1000500Y1511400D03*
X1036578Y1511210D03*
X1014690Y1511178D03*
X1010190D03*
X1005690D03*
X1031790Y1511078D03*
X1027290D03*
X1019600Y1511100D03*
X1023583Y1501593D03*
Y1507593D03*
Y1495593D03*
X995783D03*
Y1501593D03*
Y1507593D03*
X1040583Y1517883D03*
X1031799Y1534392D03*
X1031882Y1528985D03*
X1026459Y1528919D03*
X1026376Y1534326D03*
X1014867D03*
X1014950Y1528919D03*
X1020290Y1534392D03*
X1020373Y1528985D03*
X1040500Y1529290D03*
X1040583Y1523883D03*
X1062700Y1463100D03*
X1058200D03*
X1067200D03*
X1062700Y1467600D03*
X1058200D03*
X1067200D03*
X1053700Y1463100D03*
Y1467600D03*
X1062700Y1472100D03*
X1058200D03*
X1067200D03*
Y1476600D03*
X1058200D03*
X1062700D03*
X1053700Y1472100D03*
Y1476600D03*
X1078683Y1489593D03*
X1051383D03*
X1041810Y1511084D03*
X1055310D03*
X1059810D03*
X1064310D03*
X1068810D03*
X1073310D03*
X1078683Y1495593D03*
Y1501593D03*
Y1507593D03*
Y1516593D03*
X1051383Y1495593D03*
Y1501593D03*
Y1507593D03*
X1078683Y1522593D03*
G54D110*
X1384950Y573397D03*
Y579803D03*
G54D101*
X1040055Y1482511D03*
X1035055D03*
X1030055D03*
X1017255D03*
X1012255D03*
X1007255D03*
X1002255D03*
X1072855D03*
X1067855D03*
X1062855D03*
X1057855D03*
X1045055D03*
X1376200Y540900D03*
X1391200D03*
X1386200D03*
X1381200D03*
G54D111*
X1426950Y571600D03*
X1419450Y567725D03*
Y575475D03*
G54D102*
X1023290Y1521346D03*
Y1553748D03*
G54D10*
X15157Y21653D03*
Y474409D03*
X904921Y-25591D03*
Y564960D03*
X975787Y-25590D03*
X975786Y564960D03*
X1104527Y1630792D03*
X1894685Y21654D03*
X1894684Y474409D03*
G54D103*
X1007010Y1521346D03*
Y1553748D03*
G54D112*
X1500540Y528169D03*
X1502540Y533769D03*
X1498540D03*
G54D113*
G01X394744Y-485863D02*
X395618Y-484988D01*
X396273Y-483530D01*
X396710Y-481487D01*
X396273Y-479738D01*
X395400Y-478571D01*
X393871Y-477696D01*
X387976D01*
Y-495196D01*
X395181D01*
X396710Y-494030D01*
X397583Y-492279D01*
X398020Y-490238D01*
X397583Y-488196D01*
X396273Y-486446D01*
X394744Y-485863D01*
X387976D01*
G01X407441Y-495196D02*
Y-483530D01*
G01Y-485863D02*
X408533Y-484696D01*
X409625Y-483821D01*
X411153Y-483530D01*
X412244Y-483821D01*
X413555Y-484696D01*
G01X423413Y-500446D02*
X424723Y-501029D01*
X426470Y-500446D01*
X427561Y-499280D01*
X428435Y-497821D01*
X429744Y-493155D01*
X432583Y-483530D01*
G01X425596D02*
X429744Y-493155D01*
G01X448991Y-484988D02*
X447463Y-483821D01*
X446153Y-483530D01*
X444406Y-484113D01*
X443096Y-485279D01*
X442223Y-487321D01*
X442004Y-489363D01*
X442223Y-491405D01*
X443096Y-493155D01*
X444406Y-494613D01*
X446153Y-495196D01*
X447681Y-494613D01*
X448991Y-493446D01*
G01X459723Y-487321D02*
X466710D01*
X466055Y-485279D01*
X464963Y-484113D01*
X463435Y-483530D01*
X461906Y-483821D01*
X460596Y-484696D01*
X459723Y-486738D01*
X459286Y-488488D01*
Y-490238D01*
X459723Y-491988D01*
X460815Y-493738D01*
X462125Y-494904D01*
X463653Y-495196D01*
X465181Y-494613D01*
X466710Y-492863D01*
G01X502801Y-479155D02*
X501491Y-478279D01*
X499963Y-477696D01*
X498216D01*
X496251Y-478571D01*
X494723Y-480029D01*
X493631Y-481780D01*
X492758Y-484696D01*
X492539Y-487321D01*
X492976Y-489946D01*
X493631Y-491696D01*
X494941Y-493446D01*
X496470Y-494613D01*
X497998Y-495196D01*
X499526D01*
X501055Y-494613D01*
X502365Y-493738D01*
X503457Y-492572D01*
G01X519428Y-495196D02*
Y-483530D01*
G01Y-485571D02*
X518555Y-484405D01*
X517244Y-483821D01*
X515716Y-483530D01*
X514188Y-484113D01*
X512878Y-485279D01*
X512004Y-487029D01*
X511568Y-489363D01*
X512004Y-491696D01*
X512878Y-493446D01*
X514188Y-494613D01*
X515716Y-495196D01*
X517244Y-494904D01*
X518555Y-494030D01*
X519428Y-492863D01*
G01X529286Y-495196D02*
Y-483530D01*
G01Y-486446D02*
X530160Y-484988D01*
X531470Y-483821D01*
X533216Y-483530D01*
X534744Y-483821D01*
X536055Y-484988D01*
X536710Y-487029D01*
Y-495196D01*
G01X545913Y-500446D02*
X547223Y-501029D01*
X548970Y-500446D01*
X550061Y-499280D01*
X550935Y-497821D01*
X552244Y-493155D01*
X555083Y-483530D01*
G01X548096D02*
X552244Y-493155D01*
G01X567998Y-495196D02*
X566688Y-494904D01*
X565378Y-493738D01*
X564504Y-491696D01*
X564068Y-489363D01*
X564504Y-487029D01*
X565378Y-484988D01*
X566688Y-483821D01*
X567998Y-483530D01*
X569308Y-483821D01*
X570618Y-484988D01*
X571491Y-487029D01*
X571710Y-489363D01*
X571491Y-491696D01*
X570618Y-493738D01*
X569308Y-494904D01*
X567998Y-495196D01*
G01X581786D02*
Y-483530D01*
G01Y-486446D02*
X582660Y-484988D01*
X583970Y-483821D01*
X585716Y-483530D01*
X587244Y-483821D01*
X588555Y-484988D01*
X589210Y-487029D01*
Y-495196D01*
G01X616350D02*
Y-477696D01*
X624646D01*
G01X621590Y-486154D02*
X616350D01*
G01X637998Y-495779D02*
X637561Y-495488D01*
Y-494904D01*
X637998Y-494613D01*
X638435Y-494904D01*
Y-495488D01*
X637998Y-495779D01*
G01X650695Y-495196D02*
Y-477696D01*
X655061D01*
X656808Y-478571D01*
X658118Y-479738D01*
X659210Y-481487D01*
X660083Y-483530D01*
X660301Y-486446D01*
X660083Y-489363D01*
X659210Y-491405D01*
X658118Y-493155D01*
X656808Y-494321D01*
X655061Y-495196D01*
X650695D01*
G01X668631D02*
Y-477696D01*
X673871D01*
X675618Y-478571D01*
X676928Y-480613D01*
X677365Y-482946D01*
X676928Y-485279D01*
X675836Y-487029D01*
X673871Y-487905D01*
X668631D01*
G01X692244Y-485863D02*
X693118Y-484988D01*
X693773Y-483530D01*
X694210Y-481487D01*
X693773Y-479738D01*
X692900Y-478571D01*
X691371Y-477696D01*
X685476D01*
Y-495196D01*
X692681D01*
X694210Y-494030D01*
X695083Y-492279D01*
X695520Y-490238D01*
X695083Y-488196D01*
X693773Y-486446D01*
X692244Y-485863D01*
X685476D01*
G01X501071Y-450196D02*
Y-432696D01*
X506748Y-447279D01*
X512425Y-432696D01*
Y-450196D01*
G01X524248D02*
X522938Y-449904D01*
X521628Y-448738D01*
X520754Y-446696D01*
X520318Y-444363D01*
X520754Y-442029D01*
X521628Y-439988D01*
X522938Y-438821D01*
X524248Y-438530D01*
X525558Y-438821D01*
X526868Y-439988D01*
X527741Y-442029D01*
X527960Y-444363D01*
X527741Y-446696D01*
X526868Y-448738D01*
X525558Y-449904D01*
X524248Y-450196D01*
G01X545678Y-432696D02*
Y-450196D01*
G01Y-447572D02*
X544805Y-449030D01*
X543494Y-449904D01*
X541966Y-450196D01*
X540220Y-449613D01*
X538910Y-448155D01*
X538036Y-446405D01*
X537818Y-444363D01*
X538036Y-442321D01*
X538910Y-440571D01*
X540220Y-439113D01*
X541966Y-438530D01*
X543494Y-438821D01*
X544586Y-439405D01*
X545678Y-440571D01*
G01X555973Y-442321D02*
X562960D01*
X562305Y-440279D01*
X561213Y-439113D01*
X559685Y-438530D01*
X558156Y-438821D01*
X556846Y-439696D01*
X555973Y-441738D01*
X555536Y-443488D01*
Y-445238D01*
X555973Y-446988D01*
X557065Y-448738D01*
X558375Y-449904D01*
X559903Y-450196D01*
X561431Y-449613D01*
X562960Y-447863D01*
G01X576748Y-450196D02*
Y-432696D01*
G01X754448Y-495196D02*
Y-477696D01*
X751828Y-481196D01*
G01Y-495196D02*
X757068D01*
G01X767800Y-487905D02*
X769328Y-485863D01*
X770638Y-484696D01*
X772385Y-484113D01*
X773913Y-484696D01*
X775005Y-485863D01*
X775878Y-487613D01*
X776096Y-489654D01*
X775878Y-491405D01*
X775005Y-493155D01*
X773694Y-494613D01*
X772166Y-495196D01*
X770420Y-494613D01*
X768891Y-492863D01*
X768018Y-490238D01*
X767800Y-487321D01*
X768236Y-483530D01*
X768891Y-481487D01*
X769983Y-479446D01*
X771511Y-477988D01*
X773040Y-477696D01*
X774568Y-478279D01*
X775660Y-479738D01*
G01X784645Y-491696D02*
X785954Y-493738D01*
X787701Y-494904D01*
X789666Y-495196D01*
X791413Y-494904D01*
X793160Y-493446D01*
X794251Y-491696D01*
X794470Y-489946D01*
X794033Y-487905D01*
X792505Y-486446D01*
X790976Y-485863D01*
X789011D01*
G01X790976D02*
X792286Y-484988D01*
X793378Y-483530D01*
X793815Y-481780D01*
X793378Y-480029D01*
X792286Y-478571D01*
X790321Y-477696D01*
X788356Y-477988D01*
X786391Y-479155D01*
G01X806948Y-495196D02*
Y-477696D01*
X804328Y-481196D01*
G01Y-495196D02*
X809568D01*
G01X819645Y-492572D02*
X820954Y-494030D01*
X822483Y-494904D01*
X824448Y-495196D01*
X826413Y-494613D01*
X827941Y-493446D01*
X829033Y-491405D01*
X829251Y-489071D01*
X828815Y-486738D01*
X827723Y-485279D01*
X826194Y-484113D01*
X824666Y-483821D01*
X823138Y-484113D01*
X821173Y-485279D01*
X821828Y-477696D01*
X827723D01*
G01X741331Y-450196D02*
Y-432696D01*
X746571D01*
X748318Y-433571D01*
X749628Y-435613D01*
X750065Y-437946D01*
X749628Y-440279D01*
X748536Y-442029D01*
X746571Y-442905D01*
X741331D01*
G01X768001Y-434155D02*
X766691Y-433279D01*
X765163Y-432696D01*
X763416D01*
X761451Y-433571D01*
X759923Y-435029D01*
X758831Y-436780D01*
X757958Y-439696D01*
X757739Y-442321D01*
X758176Y-444946D01*
X758831Y-446696D01*
X760141Y-448446D01*
X761670Y-449613D01*
X763198Y-450196D01*
X764726D01*
X766255Y-449613D01*
X767565Y-448738D01*
X768657Y-447572D01*
G01X782444Y-440863D02*
X783318Y-439988D01*
X783973Y-438530D01*
X784410Y-436487D01*
X783973Y-434738D01*
X783100Y-433571D01*
X781571Y-432696D01*
X775676D01*
Y-450196D01*
X782881D01*
X784410Y-449030D01*
X785283Y-447279D01*
X785720Y-445238D01*
X785283Y-443196D01*
X783973Y-441446D01*
X782444Y-440863D01*
X775676D01*
G01X791648Y-456029D02*
X804748D01*
G01X810676Y-450196D02*
Y-432696D01*
X820720Y-450196D01*
Y-432696D01*
G01X833198Y-450196D02*
X831451Y-449904D01*
X829923Y-448738D01*
X828613Y-446988D01*
X827739Y-444946D01*
X827303Y-442613D01*
Y-440279D01*
X827739Y-437946D01*
X828613Y-435904D01*
X829923Y-434155D01*
X831451Y-432988D01*
X833198Y-432696D01*
X834944Y-432988D01*
X836473Y-434155D01*
X837783Y-435904D01*
X838657Y-437946D01*
X839093Y-440279D01*
Y-442613D01*
X838657Y-444946D01*
X837783Y-446988D01*
X836473Y-448738D01*
X834944Y-449904D01*
X833198Y-450196D01*
G01X884039Y-432696D02*
X889498Y-450196D01*
X894957Y-432696D01*
G01X911365Y-450196D02*
X902631D01*
Y-432696D01*
X911365D01*
G01X907871Y-441154D02*
X902631D01*
G01X920131Y-450196D02*
Y-432696D01*
X925590D01*
X927336Y-433571D01*
X928428Y-434738D01*
X928865Y-437071D01*
X928428Y-439405D01*
X927118Y-440863D01*
X925590Y-441738D01*
X920131D01*
G01X925590D02*
X928865Y-450196D01*
G01X941998Y-450779D02*
X941561Y-450488D01*
Y-449904D01*
X941998Y-449613D01*
X942435Y-449904D01*
Y-450488D01*
X941998Y-450779D01*
G01X915748Y-495196D02*
Y-477696D01*
X913128Y-481196D01*
G01Y-495196D02*
X918368D01*
G01X1087348Y-477696D02*
Y-495196D01*
G01X1082326Y-477696D02*
X1092370D01*
G01X1099171Y-495196D02*
Y-477696D01*
X1104848Y-492279D01*
X1110525Y-477696D01*
Y-495196D01*
G01X1116889D02*
X1122348Y-477696D01*
X1127807Y-495196D01*
G01X1125841Y-489071D02*
X1118854D01*
G01X1135263Y-492863D02*
X1137010Y-494321D01*
X1138975Y-495196D01*
X1140721D01*
X1142468Y-494321D01*
X1143778Y-492863D01*
X1144433Y-490821D01*
X1143996Y-488780D01*
X1142905Y-487029D01*
X1140940Y-485863D01*
X1138320Y-485279D01*
X1136791Y-484113D01*
X1136136Y-482071D01*
X1136573Y-480029D01*
X1137665Y-478571D01*
X1139193Y-477696D01*
X1140721D01*
X1142250Y-478279D01*
X1143560Y-479738D01*
G01X1152545Y-495196D02*
Y-477696D01*
G01X1160841D02*
X1152545Y-488488D01*
G01X1162151Y-495196D02*
X1156256Y-483530D01*
G01X1082981Y-432696D02*
Y-450196D01*
X1091715D01*
G01X1108778D02*
Y-438530D01*
G01Y-440571D02*
X1107905Y-439405D01*
X1106594Y-438821D01*
X1105066Y-438530D01*
X1103538Y-439113D01*
X1102228Y-440279D01*
X1101354Y-442029D01*
X1100918Y-444363D01*
X1101354Y-446696D01*
X1102228Y-448446D01*
X1103538Y-449613D01*
X1105066Y-450196D01*
X1106594Y-449904D01*
X1107905Y-449030D01*
X1108778Y-447863D01*
G01X1117763Y-455446D02*
X1119073Y-456029D01*
X1120820Y-455446D01*
X1121911Y-454280D01*
X1122785Y-452821D01*
X1124094Y-448155D01*
X1126933Y-438530D01*
G01X1119946D02*
X1124094Y-448155D01*
G01X1136573Y-442321D02*
X1143560D01*
X1142905Y-440279D01*
X1141813Y-439113D01*
X1140285Y-438530D01*
X1138756Y-438821D01*
X1137446Y-439696D01*
X1136573Y-441738D01*
X1136136Y-443488D01*
Y-445238D01*
X1136573Y-446988D01*
X1137665Y-448738D01*
X1138975Y-449904D01*
X1140503Y-450196D01*
X1142031Y-449613D01*
X1143560Y-447863D01*
G01X1154291Y-450196D02*
Y-438530D01*
G01Y-440863D02*
X1155383Y-439696D01*
X1156475Y-438821D01*
X1158003Y-438530D01*
X1159094Y-438821D01*
X1160405Y-439696D01*
G01X1312898Y-495196D02*
X1311151Y-494904D01*
X1309623Y-493738D01*
X1308313Y-491988D01*
X1307439Y-489946D01*
X1307003Y-487613D01*
Y-485279D01*
X1307439Y-482946D01*
X1308313Y-480904D01*
X1309623Y-479155D01*
X1311151Y-477988D01*
X1312898Y-477696D01*
X1314644Y-477988D01*
X1316173Y-479155D01*
X1317483Y-480904D01*
X1318357Y-482946D01*
X1318793Y-485279D01*
Y-487613D01*
X1318357Y-489946D01*
X1317483Y-491988D01*
X1316173Y-493738D01*
X1314644Y-494904D01*
X1312898Y-495196D01*
G01X1314644Y-490529D02*
X1317265Y-495196D01*
G01X1325595Y-477696D02*
Y-490238D01*
X1326468Y-492863D01*
X1328215Y-494613D01*
X1330398Y-495196D01*
X1332581Y-494613D01*
X1334328Y-492863D01*
X1335201Y-490238D01*
Y-477696D01*
G01X1345278D02*
X1350518D01*
G01X1347898D02*
Y-495196D01*
G01X1345278D02*
X1350518D01*
G01X1360376D02*
Y-477696D01*
X1370420Y-495196D01*
Y-477696D01*
G01X1387701Y-479155D02*
X1386391Y-478279D01*
X1384863Y-477696D01*
X1383116D01*
X1381151Y-478571D01*
X1379623Y-480029D01*
X1378531Y-481780D01*
X1377658Y-484696D01*
X1377439Y-487321D01*
X1377876Y-489946D01*
X1378531Y-491696D01*
X1379841Y-493446D01*
X1381370Y-494613D01*
X1382898Y-495196D01*
X1384426D01*
X1385955Y-494613D01*
X1387265Y-493738D01*
X1388357Y-492572D01*
G01X1400398Y-495196D02*
Y-487321D01*
X1396031Y-477696D01*
G01X1404765D02*
X1400398Y-487321D01*
G01X1290595Y-450196D02*
Y-432696D01*
X1294961D01*
X1296708Y-433571D01*
X1298018Y-434738D01*
X1299110Y-436487D01*
X1299983Y-438530D01*
X1300201Y-441446D01*
X1299983Y-444363D01*
X1299110Y-446405D01*
X1298018Y-448155D01*
X1296708Y-449321D01*
X1294961Y-450196D01*
X1290595D01*
G01X1309623Y-442321D02*
X1316610D01*
X1315955Y-440279D01*
X1314863Y-439113D01*
X1313335Y-438530D01*
X1311806Y-438821D01*
X1310496Y-439696D01*
X1309623Y-441738D01*
X1309186Y-443488D01*
Y-445238D01*
X1309623Y-446988D01*
X1310715Y-448738D01*
X1312025Y-449904D01*
X1313553Y-450196D01*
X1315081Y-449613D01*
X1316610Y-447863D01*
G01X1327123Y-448155D02*
X1328215Y-449321D01*
X1329743Y-450196D01*
X1331053D01*
X1332363Y-449613D01*
X1333236Y-448738D01*
X1333673Y-447572D01*
X1333455Y-445821D01*
X1332581Y-444946D01*
X1328651Y-443196D01*
X1327778Y-441154D01*
X1328215Y-439696D01*
X1329088Y-438821D01*
X1330398Y-438530D01*
X1331708Y-438821D01*
X1333018Y-439696D01*
G01X1347898Y-438530D02*
Y-450196D01*
G01Y-433863D02*
X1347461Y-433571D01*
Y-432988D01*
X1347898Y-432696D01*
X1348335Y-432988D01*
Y-433571D01*
X1347898Y-433863D01*
G01X1362341Y-454571D02*
X1363870Y-455738D01*
X1365616Y-456029D01*
X1367144Y-455738D01*
X1368455Y-454280D01*
X1369328Y-452238D01*
Y-438530D01*
G01Y-440863D02*
X1368455Y-439696D01*
X1367144Y-438821D01*
X1365616Y-438530D01*
X1363870Y-439113D01*
X1362778Y-440279D01*
X1361904Y-442321D01*
X1361468Y-444363D01*
X1361686Y-446113D01*
X1362560Y-448155D01*
X1363870Y-449613D01*
X1365616Y-450196D01*
X1366926Y-449904D01*
X1368455Y-448738D01*
X1369328Y-447572D01*
G01X1379186Y-450196D02*
Y-438530D01*
G01Y-441446D02*
X1380060Y-439988D01*
X1381370Y-438821D01*
X1383116Y-438530D01*
X1384644Y-438821D01*
X1385955Y-439988D01*
X1386610Y-442029D01*
Y-450196D01*
G01X1397123Y-442321D02*
X1404110D01*
X1403455Y-440279D01*
X1402363Y-439113D01*
X1400835Y-438530D01*
X1399306Y-438821D01*
X1397996Y-439696D01*
X1397123Y-441738D01*
X1396686Y-443488D01*
Y-445238D01*
X1397123Y-446988D01*
X1398215Y-448738D01*
X1399525Y-449904D01*
X1401053Y-450196D01*
X1402581Y-449613D01*
X1404110Y-447863D01*
G01X1414841Y-450196D02*
Y-438530D01*
G01Y-440863D02*
X1415933Y-439696D01*
X1417025Y-438821D01*
X1418553Y-438530D01*
X1419644Y-438821D01*
X1420955Y-439696D01*
G01X1461598Y-477696D02*
X1459851Y-478279D01*
X1458541Y-479738D01*
X1457668Y-481487D01*
X1457013Y-483821D01*
X1456795Y-486446D01*
X1457013Y-489071D01*
X1457668Y-491405D01*
X1458541Y-493155D01*
X1459851Y-494613D01*
X1461598Y-495196D01*
X1463344Y-494613D01*
X1464655Y-493155D01*
X1465528Y-491405D01*
X1466183Y-489071D01*
X1466401Y-486446D01*
X1466183Y-483821D01*
X1465528Y-481487D01*
X1464655Y-479738D01*
X1463344Y-478279D01*
X1461598Y-477696D01*
G01X1474950Y-487905D02*
X1476478Y-485863D01*
X1477788Y-484696D01*
X1479535Y-484113D01*
X1481063Y-484696D01*
X1482155Y-485863D01*
X1483028Y-487613D01*
X1483246Y-489654D01*
X1483028Y-491405D01*
X1482155Y-493155D01*
X1480844Y-494613D01*
X1479316Y-495196D01*
X1477570Y-494613D01*
X1476041Y-492863D01*
X1475168Y-490238D01*
X1474950Y-487321D01*
X1475386Y-483530D01*
X1476041Y-481487D01*
X1477133Y-479446D01*
X1478661Y-477988D01*
X1480190Y-477696D01*
X1481718Y-478279D01*
X1482810Y-479738D01*
G01X1492668Y-495779D02*
X1500528Y-477696D01*
G01X1514098D02*
X1512351Y-478279D01*
X1511041Y-479738D01*
X1510168Y-481487D01*
X1509513Y-483821D01*
X1509295Y-486446D01*
X1509513Y-489071D01*
X1510168Y-491405D01*
X1511041Y-493155D01*
X1512351Y-494613D01*
X1514098Y-495196D01*
X1515844Y-494613D01*
X1517155Y-493155D01*
X1518028Y-491405D01*
X1518683Y-489071D01*
X1518901Y-486446D01*
X1518683Y-483821D01*
X1518028Y-481487D01*
X1517155Y-479738D01*
X1515844Y-478279D01*
X1514098Y-477696D01*
G01X1527886Y-493155D02*
X1529415Y-494613D01*
X1531161Y-495196D01*
X1532908Y-494613D01*
X1534436Y-492863D01*
X1535528Y-490238D01*
X1535965Y-487613D01*
Y-484405D01*
X1535528Y-481780D01*
X1534436Y-479446D01*
X1533126Y-478279D01*
X1531598Y-477696D01*
X1529851Y-478279D01*
X1528541Y-479446D01*
X1527668Y-481196D01*
X1527231Y-483530D01*
X1527668Y-485571D01*
X1528760Y-487613D01*
X1530070Y-488780D01*
X1531598Y-489071D01*
X1533344Y-488488D01*
X1534655Y-487029D01*
X1535965Y-484405D01*
G01X1545168Y-495779D02*
X1553028Y-477696D01*
G01X1562450Y-480613D02*
X1563760Y-478863D01*
X1565288Y-477988D01*
X1567035Y-477696D01*
X1569218Y-478279D01*
X1570746Y-479738D01*
X1571183Y-481487D01*
X1570965Y-483238D01*
X1570091Y-484696D01*
X1565725Y-487613D01*
X1563760Y-489654D01*
X1562450Y-492572D01*
X1562013Y-495196D01*
X1571183D01*
G01X1584098Y-477696D02*
X1582351Y-478279D01*
X1581041Y-479738D01*
X1580168Y-481487D01*
X1579513Y-483821D01*
X1579295Y-486446D01*
X1579513Y-489071D01*
X1580168Y-491405D01*
X1581041Y-493155D01*
X1582351Y-494613D01*
X1584098Y-495196D01*
X1585844Y-494613D01*
X1587155Y-493155D01*
X1588028Y-491405D01*
X1588683Y-489071D01*
X1588901Y-486446D01*
X1588683Y-483821D01*
X1588028Y-481487D01*
X1587155Y-479738D01*
X1585844Y-478279D01*
X1584098Y-477696D01*
G01X1601598Y-495196D02*
Y-477696D01*
X1598978Y-481196D01*
G01Y-495196D02*
X1604218D01*
G01X1618661D02*
X1619098Y-491405D01*
X1619753Y-488196D01*
X1620626Y-485279D01*
X1621718Y-482071D01*
X1623465Y-477696D01*
X1614731D01*
G01X1509295Y-450196D02*
Y-432696D01*
X1513661D01*
X1515408Y-433571D01*
X1516718Y-434738D01*
X1517810Y-436487D01*
X1518683Y-438530D01*
X1518901Y-441446D01*
X1518683Y-444363D01*
X1517810Y-446405D01*
X1516718Y-448155D01*
X1515408Y-449321D01*
X1513661Y-450196D01*
X1509295D01*
G01X1535528D02*
Y-438530D01*
G01Y-440571D02*
X1534655Y-439405D01*
X1533344Y-438821D01*
X1531816Y-438530D01*
X1530288Y-439113D01*
X1528978Y-440279D01*
X1528104Y-442029D01*
X1527668Y-444363D01*
X1528104Y-446696D01*
X1528978Y-448446D01*
X1530288Y-449613D01*
X1531816Y-450196D01*
X1533344Y-449904D01*
X1534655Y-449030D01*
X1535528Y-447863D01*
G01X1549098Y-432696D02*
Y-450196D01*
G01X1546041Y-438530D02*
X1552155D01*
G01X1563323Y-442321D02*
X1570310D01*
X1569655Y-440279D01*
X1568563Y-439113D01*
X1567035Y-438530D01*
X1565506Y-438821D01*
X1564196Y-439696D01*
X1563323Y-441738D01*
X1562886Y-443488D01*
Y-445238D01*
X1563323Y-446988D01*
X1564415Y-448738D01*
X1565725Y-449904D01*
X1567253Y-450196D01*
X1568781Y-449613D01*
X1570310Y-447863D01*
G54D20*
X59937Y183961D03*
Y636717D03*
Y1089473D03*
X108363Y995525D03*
X112500Y995580D03*
X184149Y184061D03*
X175063Y583525D03*
X179200Y583580D03*
X188649Y626217D03*
X306955Y68479D03*
X314370Y121941D03*
X308362Y184061D03*
X308262Y636817D03*
Y1089573D03*
X323813Y121922D03*
X328321Y121899D03*
X318909Y121943D03*
X333021Y121955D03*
X365162Y81270D03*
X432574Y184061D03*
Y636717D03*
X447173Y1072026D03*
X442473D03*
X556787Y183961D03*
X549279Y516631D03*
X553279D03*
X556787Y636717D03*
Y1089573D03*
X580279Y516631D03*
X557279Y563631D03*
X592779Y570631D03*
X579718Y570697D03*
X571540Y570665D03*
X615100Y516900D03*
X611910Y562574D03*
X637213Y585955D03*
X681000Y183961D03*
X685500Y636717D03*
X680400Y1097600D03*
X878673Y807903D03*
X883400Y807932D03*
X881448Y1355107D03*
X881420Y1346988D03*
X882000Y1435800D03*
X873000D03*
X893050Y1482600D03*
X879321Y1482561D03*
X883947Y1482570D03*
X860000Y1501300D03*
X850500D03*
X914600Y909000D03*
X927861Y959507D03*
X921600Y978500D03*
X916500Y959400D03*
X925053Y1028685D03*
X916769Y1028739D03*
X936959Y1363590D03*
X932294Y1373148D03*
X936964Y1349912D03*
X922500Y1503000D03*
X918500D03*
X941000Y1557000D03*
X926500Y1550000D03*
X957000Y908300D03*
X970500D03*
X952500D03*
X954900Y953700D03*
X950400D03*
X959400D03*
X955000Y979300D03*
X964000D03*
X945790Y950462D03*
X955700Y1024100D03*
X951200D03*
X946700D03*
X951525Y1372957D03*
X947159Y1361887D03*
X950300Y1503000D03*
X988573Y1506512D03*
X962000Y1557000D03*
X949000D03*
X972413Y1553466D03*
X1038712Y-41958D03*
X1004100Y-73432D03*
X1035973Y827503D03*
X1034400Y905000D03*
X1002194Y978140D03*
X1006694D03*
X1007849Y1027143D03*
X1003194Y1027140D03*
X993649Y1027143D03*
X1012494Y1027240D03*
X998439Y1027137D03*
X1028000Y1070300D03*
X1022400Y1118100D03*
X1031400D03*
X1026900D03*
X1017800Y1140800D03*
X1008700D03*
X995000D03*
X1009500Y1184300D03*
X1014500D03*
X1004500D03*
X1061325Y-47400D03*
X1074400Y-45732D03*
X1040773Y827503D03*
X1054419Y832253D03*
X1048400Y905000D03*
X1057700D03*
X1064918Y938949D03*
X1069918D03*
X1087000Y1070300D03*
X1078000D03*
X1041500D03*
X1087700Y1119200D03*
X1074500Y1119300D03*
X1079000D03*
X1070155Y1119303D03*
X1083355D03*
X1115200Y1070400D03*
X1128900D03*
X1119500Y1118500D03*
X1124100D03*
X1115000D03*
X1176100Y262800D03*
X1176835Y611232D03*
X1192300Y265168D03*
X1194600Y292700D03*
X1197100Y272500D03*
X1250410Y233009D03*
X1327921Y82755D03*
X1299569Y87491D03*
X1315115Y130400D03*
X1324207Y130403D03*
X1319797Y130388D03*
X1328534D03*
X1312000Y165961D03*
X1322000D03*
X1326400Y178361D03*
X1321900D03*
X1312000Y618717D03*
X1322000D03*
X1326500Y631117D03*
X1322000D03*
X1309600Y1071473D03*
X1317400Y1071500D03*
X1326500Y1083873D03*
X1322000D03*
X1332934Y130388D03*
X1421969Y527957D03*
X1436213Y165961D03*
X1446213D03*
X1450713Y178361D03*
X1446013D03*
X1463085Y503185D03*
X1452200Y572400D03*
X1470700D03*
X1437200Y562900D03*
X1436213Y618717D03*
X1446213D03*
X1450713Y631117D03*
X1446013D03*
X1436213Y1071473D03*
X1446213D03*
X1450713Y1083873D03*
X1446013D03*
X1481938Y503070D03*
X1502400Y547450D03*
X1560425Y165961D03*
X1570425D03*
X1570125Y178361D03*
X1560425Y618717D03*
X1570425D03*
X1570225Y631117D03*
X1560425Y1071473D03*
X1570425D03*
Y1083973D03*
X1574925Y178361D03*
Y631117D03*
Y1083973D03*
X1684638Y165961D03*
X1694638D03*
X1699138Y178361D03*
X1694438D03*
X1684638Y618717D03*
X1694638D03*
X1699138Y631117D03*
X1694438D03*
X1684638Y1071473D03*
X1694638D03*
X1699138Y1083873D03*
X1694438D03*
X1750163Y1007525D03*
X1754300Y1007580D03*
X1808850Y165961D03*
Y618717D03*
X1805250Y1071273D03*
X1845517Y161775D03*
X1841017D03*
X1818850Y165961D03*
X1823350Y178361D03*
X1818650D03*
X1818850Y618717D03*
X1823350Y631117D03*
X1818650D03*
X1845417Y614531D03*
X1840917D03*
X1815250Y1071273D03*
X1823350Y1083873D03*
X1818650D03*
X1838074Y1088995D03*
X1836200Y1133220D03*
X1878900Y187544D03*
Y640300D03*
X1876662Y1058726D03*
X1872162D03*
G54D104*
X1065716Y1546420D03*
X1094000D03*
G54D11*
G01X363248Y-425196D02*
Y-505196D01*
G01D02*
X1639148D01*
G01X359248Y-409196D02*
G02I-12000J0D01*
G01X354098D02*
G02I-6850J0D01*
G01X347248Y-425196D02*
Y-393196D01*
G01X363248Y-425196D02*
X1639148D01*
G01X363248Y-460696D02*
X1639148D01*
G01X363248Y-409196D02*
X331248D01*
G01X720748Y-425196D02*
Y-505196D01*
G01X858248Y-425196D02*
Y-505196D01*
G01X973248Y-425196D02*
Y-505196D01*
G01X1271648Y-425196D02*
Y-505196D01*
G01X1441648Y-425196D02*
Y-505196D01*
G01X1639148Y-425196D02*
Y-505196D01*
G01X1667148Y-409196D02*
G02I-12000J0D01*
G01X1661998D02*
G02I-6850J0D01*
G01X1655148Y-425196D02*
Y-393196D01*
G01X1671148Y-409196D02*
X1639148D01*
X24508Y5500D03*
X5500Y61492D03*
Y56492D03*
Y51492D03*
Y46492D03*
Y41492D03*
Y66492D03*
Y81492D03*
Y76492D03*
Y96492D03*
Y91492D03*
Y86492D03*
Y71492D03*
Y101492D03*
Y111492D03*
Y116492D03*
Y106492D03*
Y126492D03*
Y121492D03*
Y141492D03*
Y151492D03*
Y161492D03*
Y156492D03*
Y146492D03*
Y131492D03*
Y136492D03*
Y181492D03*
Y191492D03*
Y201492D03*
Y211492D03*
Y171492D03*
Y206492D03*
Y196492D03*
Y176492D03*
Y166492D03*
Y186492D03*
Y231492D03*
Y241492D03*
Y251492D03*
Y261492D03*
Y221492D03*
Y256492D03*
Y246492D03*
Y226492D03*
Y216492D03*
Y236492D03*
Y281492D03*
Y291492D03*
Y301492D03*
Y271492D03*
Y306492D03*
Y296492D03*
Y286492D03*
Y276492D03*
Y266492D03*
Y331492D03*
Y341492D03*
Y351492D03*
Y311492D03*
Y321492D03*
Y356492D03*
Y346492D03*
Y336492D03*
Y326492D03*
Y316492D03*
Y381492D03*
Y391492D03*
Y401492D03*
Y361492D03*
Y371492D03*
Y406492D03*
Y396492D03*
Y386492D03*
Y376492D03*
Y366492D03*
Y451492D03*
Y441492D03*
Y431492D03*
Y421492D03*
Y411492D03*
Y416492D03*
Y436492D03*
Y446492D03*
Y426492D03*
Y501492D03*
Y456492D03*
Y496492D03*
Y531492D03*
Y551492D03*
Y541492D03*
Y521492D03*
Y511492D03*
Y536492D03*
Y546492D03*
Y506492D03*
Y516492D03*
Y526492D03*
Y581492D03*
Y591492D03*
Y571492D03*
Y561492D03*
Y586492D03*
Y596492D03*
Y556492D03*
Y566492D03*
Y576492D03*
Y631492D03*
Y641492D03*
Y621492D03*
Y611492D03*
Y601492D03*
Y636492D03*
Y646492D03*
Y606492D03*
Y616492D03*
Y626492D03*
Y681492D03*
Y691492D03*
Y671492D03*
Y661492D03*
Y651492D03*
Y686492D03*
Y696492D03*
Y656492D03*
Y666492D03*
Y676492D03*
Y731492D03*
Y741492D03*
Y721492D03*
Y711492D03*
Y701492D03*
Y736492D03*
Y706492D03*
Y716492D03*
Y726492D03*
Y781492D03*
Y791492D03*
Y771492D03*
Y761492D03*
Y751492D03*
Y786492D03*
Y746492D03*
Y756492D03*
Y766492D03*
Y776492D03*
Y831492D03*
Y841492D03*
Y821492D03*
Y811492D03*
Y801492D03*
Y836492D03*
Y796492D03*
Y806492D03*
Y816492D03*
Y826492D03*
Y881492D03*
Y871492D03*
Y861492D03*
Y851492D03*
Y886492D03*
Y846492D03*
Y856492D03*
Y866492D03*
Y876492D03*
Y931492D03*
Y921492D03*
Y911492D03*
Y901492D03*
Y891492D03*
Y936492D03*
Y896492D03*
Y906492D03*
Y916492D03*
Y926492D03*
Y976492D03*
Y981492D03*
Y986492D03*
Y966492D03*
Y956492D03*
Y961492D03*
Y971492D03*
Y951492D03*
Y941492D03*
Y946492D03*
Y991492D03*
Y996492D03*
Y1001492D03*
Y1006492D03*
Y1026492D03*
Y1016492D03*
Y1011492D03*
Y1021492D03*
Y1031492D03*
Y1036492D03*
Y1066492D03*
Y1056492D03*
Y1046492D03*
Y1041492D03*
Y1051492D03*
Y1061492D03*
Y1071492D03*
Y1081492D03*
Y1076492D03*
Y1121492D03*
Y1131492D03*
Y1111492D03*
Y1101492D03*
Y1091492D03*
Y1086492D03*
Y1096492D03*
Y1106492D03*
Y1116492D03*
Y1126492D03*
Y1171492D03*
Y1161492D03*
Y1151492D03*
Y1141492D03*
Y1136492D03*
Y1146492D03*
Y1156492D03*
Y1166492D03*
Y1176492D03*
Y1221492D03*
Y1211492D03*
Y1201492D03*
Y1191492D03*
Y1181492D03*
Y1186492D03*
Y1196492D03*
Y1206492D03*
Y1216492D03*
Y1226492D03*
Y1271492D03*
Y1261492D03*
Y1251492D03*
Y1241492D03*
Y1231492D03*
Y1236492D03*
Y1246492D03*
Y1256492D03*
Y1266492D03*
Y1276492D03*
Y1321492D03*
Y1311492D03*
Y1301492D03*
Y1291492D03*
Y1281492D03*
Y1286492D03*
Y1296492D03*
Y1306492D03*
Y1316492D03*
X8983Y1368303D03*
X13983D03*
X18983D03*
X23983D03*
X5500Y1361492D03*
Y1351492D03*
Y1341492D03*
Y1331492D03*
Y1336492D03*
Y1346492D03*
Y1356492D03*
Y1326492D03*
X29508Y5500D03*
X39508D03*
X34508D03*
X44508D03*
X64508D03*
X69508D03*
X54508D03*
X49508D03*
X59508D03*
X28983Y1368303D03*
X33983D03*
X38983D03*
X43983D03*
X48983D03*
X53983D03*
X58983D03*
X63983D03*
X68983D03*
X114508Y5500D03*
X119508D03*
X104508D03*
X94508D03*
X84508D03*
X74508D03*
X79508D03*
X89508D03*
X99508D03*
X109508D03*
X119763Y550725D03*
Y546225D03*
Y555225D03*
X83100Y984800D03*
X78600D03*
X83100Y980300D03*
X78600D03*
Y989300D03*
X83100D03*
X73983Y1368303D03*
X78983D03*
X83983D03*
X88983D03*
X93983D03*
X98983D03*
X107374Y1369303D03*
X112374D03*
X117374D03*
X134508Y5500D03*
X124508D03*
X129508D03*
X169508D03*
X159508D03*
X149508D03*
X139508D03*
X154508D03*
X164508D03*
X144508D03*
X124263Y546225D03*
Y550725D03*
Y555225D03*
X141978Y958572D03*
X142006Y978425D03*
X122374Y1369303D03*
X127374D03*
X132374D03*
X137374D03*
X142374D03*
X147374D03*
X152374D03*
X157374D03*
X162374D03*
X167374D03*
X209508Y5500D03*
X199508D03*
X189508D03*
X179508D03*
X204508D03*
X214508D03*
X174508D03*
X184508D03*
X194508D03*
X209863Y566625D03*
X199102Y969717D03*
Y974717D03*
X183584Y974789D03*
Y969789D03*
X199392Y985113D03*
X183551Y984789D03*
X212063Y976725D03*
X203063D03*
X207563D03*
X216563D03*
X212063Y981725D03*
X216563D03*
X207563D03*
X203063D03*
X199392Y990113D03*
X183551Y989789D03*
X172374Y1369303D03*
X177374D03*
X182374D03*
X187374D03*
X192374D03*
X197374D03*
X202374D03*
X207374D03*
X212374D03*
X217374D03*
X259508Y5500D03*
X249508D03*
X239508D03*
X229508D03*
X219508D03*
X224508D03*
X234508D03*
X244508D03*
X254508D03*
X264508D03*
X250650Y556997D03*
Y561997D03*
X265545Y556794D03*
Y561794D03*
X250661Y572936D03*
Y577936D03*
X265590Y572801D03*
Y577801D03*
X225563Y976725D03*
X221063D03*
X225563Y981725D03*
X221063D03*
X222374Y1369303D03*
X227374D03*
X232374D03*
X237374D03*
X242374D03*
X247374D03*
X252374D03*
X257374D03*
X262374D03*
X309508Y5500D03*
X299508D03*
X289508D03*
X279508D03*
X269508D03*
X304508D03*
X314508D03*
X274508D03*
X284508D03*
X294508D03*
X269763Y569725D03*
X287763D03*
X292263D03*
X274263D03*
X283263D03*
X278763D03*
X283263Y564725D03*
X287763D03*
X292263D03*
X274263D03*
X269763D03*
X278763D03*
X267374Y1369303D03*
X272374D03*
X277374D03*
X282374D03*
X287374D03*
X292374D03*
X297374D03*
X302374D03*
X307374D03*
X312374D03*
X359508Y5500D03*
X349508D03*
X339508D03*
X329508D03*
X319508D03*
X324508D03*
X334508D03*
X344508D03*
X354508D03*
X333983Y1368303D03*
X338983D03*
X343983D03*
X348983D03*
X353983D03*
X358983D03*
X363983D03*
X317374Y1369303D03*
X322374D03*
X327374D03*
X395075Y18639D03*
Y13639D03*
X389508Y5500D03*
X379508D03*
X369508D03*
X364508D03*
X374508D03*
X384508D03*
X394508D03*
X395075Y43639D03*
Y38639D03*
Y33639D03*
Y28639D03*
Y23639D03*
X399000Y62000D03*
X396000Y55500D03*
X396075Y50248D03*
X368983Y1368303D03*
X373983D03*
X378983D03*
X383983D03*
X388983D03*
X393983D03*
X398983D03*
X403983D03*
X408983D03*
X413983D03*
X418983D03*
X423983D03*
X428983D03*
X433983D03*
X438983D03*
X443983D03*
X448983D03*
X453983D03*
X458983D03*
X463983D03*
X468983D03*
X473983D03*
X478983D03*
X483983D03*
X488983D03*
X493983D03*
X498983D03*
X503983D03*
X508983D03*
X517374Y1369303D03*
X522374D03*
X527374D03*
X532374D03*
X537374D03*
X542374D03*
X547374D03*
X552374D03*
X557374D03*
X597051Y7699D03*
Y12699D03*
Y17699D03*
X604146Y5500D03*
X597051Y22699D03*
Y27699D03*
Y32699D03*
Y37699D03*
Y42699D03*
X589000Y64000D03*
X594000Y61500D03*
X596000Y56500D03*
X596051Y51090D03*
X567374Y1369303D03*
X572374D03*
X577374D03*
X582374D03*
X587374D03*
X592374D03*
X597374D03*
X602374D03*
X562374D03*
X609146Y5500D03*
X619146D03*
X614146D03*
X629146D03*
X639146D03*
X649146D03*
X654146D03*
X644146D03*
X634146D03*
X624146D03*
X637592Y593186D03*
X641792D03*
Y597386D03*
X637592D03*
X633392Y593186D03*
Y597386D03*
X629192Y593186D03*
Y597386D03*
X641792Y605786D03*
Y601586D03*
X637592D03*
Y605786D03*
X633392D03*
Y601586D03*
X629192D03*
Y605786D03*
X617374Y1369303D03*
X622374D03*
X627374D03*
X632374D03*
X637374D03*
X642374D03*
X647374D03*
X652374D03*
X607374D03*
X612374D03*
X679146Y5500D03*
X689146D03*
X694146D03*
X684146D03*
X659146D03*
X669146D03*
X664146D03*
X674146D03*
X699146D03*
X675913Y586555D03*
Y592955D03*
Y598155D03*
X672082Y582834D03*
X666882D03*
X661682D03*
X656482D03*
X695413Y600755D03*
X699613D03*
X669482Y613934D03*
Y609734D03*
X665282D03*
Y613934D03*
X661082D03*
Y609734D03*
X656882Y613934D03*
Y609734D03*
X675913Y603355D03*
X695413Y604955D03*
X691213Y613355D03*
X695413D03*
X699613D03*
X691213Y609155D03*
X695413D03*
X699613Y604955D03*
Y609155D03*
X702483Y945989D03*
X667374Y1369303D03*
X672374D03*
X677374D03*
X682374D03*
X687374D03*
X692374D03*
X697374D03*
X702374D03*
X657374D03*
X662374D03*
X749146Y5500D03*
X709146D03*
X719146D03*
X729146D03*
X739146D03*
X744146D03*
X734146D03*
X724146D03*
X714146D03*
X704146D03*
X703813Y592355D03*
Y596555D03*
Y600755D03*
X704399Y626799D03*
Y618399D03*
Y622599D03*
X703813Y613355D03*
Y609155D03*
Y604955D03*
X721552Y951317D03*
X725852Y951067D03*
X747374Y1369303D03*
X742374D03*
X717374D03*
X722374D03*
X727374D03*
X732374D03*
X737374D03*
X707374D03*
X712374D03*
X795969Y-1374D03*
X759146Y5500D03*
X769146D03*
X774146D03*
X764146D03*
X754146D03*
X779146D03*
X755500Y1374500D03*
X752500Y1370500D03*
X757287Y1380873D03*
Y1385873D03*
Y1390873D03*
Y1395873D03*
Y1400873D03*
Y1405873D03*
Y1410873D03*
Y1415873D03*
Y1420873D03*
Y1425873D03*
Y1430873D03*
Y1435873D03*
Y1440873D03*
Y1445873D03*
X766156Y1462004D03*
X771156D03*
X790500Y1466500D03*
X786000Y1463500D03*
X756287Y1459264D03*
Y1454264D03*
X779547Y1463004D03*
X792902Y1477964D03*
Y1487964D03*
Y1497964D03*
Y1507964D03*
Y1517964D03*
Y1512964D03*
Y1472964D03*
Y1482964D03*
Y1492964D03*
Y1502964D03*
Y1562964D03*
Y1527964D03*
Y1537964D03*
Y1547964D03*
Y1557964D03*
Y1567964D03*
Y1522964D03*
Y1532964D03*
Y1542964D03*
Y1552964D03*
Y1612964D03*
Y1602964D03*
Y1592964D03*
Y1582964D03*
Y1572964D03*
Y1577964D03*
Y1587964D03*
Y1597964D03*
Y1607964D03*
X797902Y1652964D03*
X792902D03*
Y1642964D03*
Y1632964D03*
Y1622964D03*
Y1627964D03*
Y1637964D03*
Y1647964D03*
Y1617964D03*
X872642Y-140575D03*
Y-135575D03*
Y-130575D03*
Y-125575D03*
X890264Y-147256D03*
X880264D03*
X875264D03*
X885264D03*
X895264D03*
X872642Y-80575D03*
Y-120575D03*
Y-115575D03*
Y-110575D03*
Y-105575D03*
Y-100575D03*
Y-95575D03*
Y-90575D03*
Y-85575D03*
Y-30575D03*
Y-35575D03*
Y-40575D03*
Y-45575D03*
Y-50575D03*
Y-55575D03*
Y-60575D03*
Y-65575D03*
Y-70575D03*
Y-75575D03*
Y-20575D03*
Y-25575D03*
X940264Y-147256D03*
X930264D03*
X925264D03*
X935264D03*
X920264D03*
X910264D03*
X900264D03*
X905264D03*
X915264D03*
X960264D03*
X950264D03*
X955264D03*
X965264D03*
X945264D03*
X990264D03*
X980264D03*
X970264D03*
X975264D03*
X985264D03*
X1010264D03*
X1000264D03*
X1005264D03*
X1015264D03*
X995264D03*
X1040264D03*
X1030264D03*
X1020264D03*
X1025264D03*
X1035264D03*
X1060264D03*
X1050264D03*
X1055264D03*
X1065264D03*
X1045264D03*
X1080264D03*
X1070264D03*
X1075264D03*
X1085264D03*
X1078098Y1652768D03*
X1073098D03*
X1083098D03*
X1088098D03*
X1110264Y-147256D03*
X1100264D03*
X1090264D03*
X1105264D03*
X1095264D03*
X1130264D03*
X1120264D03*
X1115264D03*
X1125264D03*
X1135264D03*
X1093098Y1652768D03*
X1133098D03*
X1123098D03*
X1113098D03*
X1103098D03*
X1108098D03*
X1118098D03*
X1128098D03*
X1098098D03*
X1170264Y-147256D03*
X1155264D03*
X1175602Y-137594D03*
Y-127594D03*
X1160264Y-147256D03*
X1150264D03*
X1140264D03*
X1145264D03*
X1175602Y-132594D03*
Y-142594D03*
X1165264Y-147256D03*
X1175602Y-117594D03*
Y-107594D03*
Y-97594D03*
Y-87594D03*
Y-77594D03*
Y-82594D03*
Y-92594D03*
Y-102594D03*
Y-112594D03*
Y-122594D03*
Y-67594D03*
Y-57594D03*
Y-47594D03*
Y-37594D03*
Y-32594D03*
Y-42594D03*
Y-52594D03*
Y-62594D03*
Y-72594D03*
Y-17594D03*
Y-27594D03*
X1180500Y4000D03*
X1176500Y-500D03*
X1175602Y-22594D03*
Y-12594D03*
Y-7594D03*
X1162000Y1371500D03*
X1169783Y1369303D03*
X1179783D03*
X1174783D03*
X1184783D03*
X1158673Y1417067D03*
Y1407067D03*
Y1397067D03*
Y1387067D03*
Y1377067D03*
Y1412067D03*
Y1402067D03*
Y1392067D03*
Y1382067D03*
Y1422067D03*
Y1442067D03*
Y1452067D03*
X1158500Y1468500D03*
X1158673Y1457067D03*
Y1447067D03*
Y1437067D03*
Y1427067D03*
Y1462067D03*
Y1432067D03*
X1161000Y1474500D03*
X1166673Y1477941D03*
X1171673D03*
X1181673D03*
X1176673D03*
X1143098Y1652768D03*
X1183098D03*
X1173098D03*
X1163098D03*
X1153098D03*
X1158098D03*
X1168098D03*
X1178098D03*
X1138098D03*
X1148098D03*
X1191382Y5500D03*
X1196382D03*
X1186382D03*
X1201382D03*
X1211382D03*
X1221382D03*
X1231382D03*
X1226382D03*
X1216382D03*
X1206382D03*
X1199783Y1369303D03*
X1209783D03*
X1219783D03*
X1229783D03*
X1189783D03*
X1224783D03*
X1214783D03*
X1204783D03*
X1194783D03*
X1191673Y1477941D03*
X1201673D03*
X1214972Y1482642D03*
Y1517642D03*
Y1487642D03*
Y1497642D03*
Y1507642D03*
Y1512642D03*
Y1502642D03*
Y1492642D03*
X1206673Y1477941D03*
X1196673D03*
X1186673D03*
X1211673D03*
X1214972Y1567642D03*
Y1527642D03*
Y1537642D03*
Y1547642D03*
Y1557642D03*
Y1562642D03*
Y1552642D03*
Y1542642D03*
Y1532642D03*
Y1522642D03*
Y1577642D03*
Y1587642D03*
Y1597642D03*
Y1607642D03*
Y1612642D03*
Y1602642D03*
Y1592642D03*
Y1582642D03*
Y1572642D03*
Y1617642D03*
Y1627642D03*
Y1637642D03*
X1213098Y1652768D03*
X1193098D03*
X1203098D03*
X1208098D03*
X1214972Y1642642D03*
Y1632642D03*
X1188098Y1652768D03*
X1198098D03*
X1214972Y1622642D03*
Y1647642D03*
X1251382Y5500D03*
X1261382D03*
X1271382D03*
X1281382D03*
X1276382D03*
X1266382D03*
X1256382D03*
X1241382D03*
X1246382D03*
X1236382D03*
X1249783Y1369303D03*
X1259783D03*
X1269783D03*
X1279783D03*
X1239783D03*
X1274783D03*
X1264783D03*
X1254783D03*
X1234783D03*
X1244783D03*
X1301382Y5500D03*
X1311382D03*
X1296382D03*
X1316382D03*
X1306382D03*
X1291382D03*
X1286382D03*
X1326382D03*
X1321382D03*
X1299783Y1369303D03*
X1309783D03*
X1319783D03*
X1329783D03*
X1289783D03*
X1324783D03*
X1314783D03*
X1304783D03*
X1294783D03*
X1284783D03*
X1363579Y19821D03*
Y14821D03*
Y9821D03*
X1351382Y5500D03*
X1356382D03*
X1346382D03*
X1336382D03*
X1341382D03*
X1331382D03*
X1363579Y44821D03*
Y39821D03*
Y34821D03*
Y29821D03*
Y24821D03*
X1374000Y64500D03*
X1363579Y51618D03*
X1370200Y550500D03*
X1366000D03*
X1378100Y530200D03*
Y534400D03*
X1365500Y538600D03*
X1369700D03*
X1365500Y534400D03*
X1369700D03*
X1373900D03*
X1365500Y530200D03*
X1369700D03*
X1373900D03*
X1375900Y568500D03*
X1366000Y563100D03*
X1370200D03*
Y554700D03*
X1366000D03*
X1370200Y558900D03*
X1366000D03*
X1373700Y582900D03*
X1369500D03*
X1377900Y587100D03*
Y591300D03*
Y595500D03*
X1373700D03*
Y591300D03*
Y587100D03*
X1369500Y595500D03*
Y591300D03*
Y587100D03*
X1377900Y599700D03*
X1373700D03*
X1369500D03*
X1349783Y1369303D03*
X1359783D03*
X1369783D03*
X1339783D03*
X1374783D03*
X1364783D03*
X1354783D03*
X1344783D03*
X1334783D03*
X1396500Y549500D03*
X1386500Y534400D03*
Y530200D03*
X1382300D03*
Y534400D03*
X1396500Y559900D03*
Y554700D03*
Y565100D03*
X1393000Y568500D03*
X1387300D03*
X1381600D03*
X1382100Y587100D03*
X1386300D03*
X1399783Y1369303D03*
X1409783D03*
X1419783D03*
X1379783D03*
X1389783D03*
X1404783D03*
X1414783D03*
X1424783D03*
X1394783D03*
X1384783D03*
X1434441Y590424D03*
X1434581Y586136D03*
X1449783Y1369303D03*
X1459783D03*
X1469783D03*
X1429783D03*
X1439783D03*
X1444783D03*
X1454783D03*
X1464783D03*
X1474783D03*
X1434783D03*
X1499783D03*
X1509783D03*
X1519783D03*
X1479783D03*
X1489783D03*
X1494783D03*
X1484783D03*
X1504783D03*
X1514783D03*
X1565555Y16517D03*
X1568030Y5500D03*
X1565555Y21517D03*
Y26517D03*
Y31517D03*
Y36517D03*
Y41517D03*
X1557000Y64500D03*
X1561500Y62000D03*
X1564000Y57500D03*
X1564555Y52124D03*
X1549783Y1369303D03*
X1559783D03*
X1569783D03*
X1529783D03*
X1539783D03*
X1524783D03*
X1534783D03*
X1544783D03*
X1554783D03*
X1564783D03*
X1603030Y5500D03*
X1613030D03*
X1573030D03*
X1583030D03*
X1593030D03*
X1618030D03*
X1608030D03*
X1598030D03*
X1588030D03*
X1578030D03*
X1614783Y1369303D03*
X1604783D03*
X1599783D03*
X1609783D03*
X1619783D03*
X1579783D03*
X1589783D03*
X1574783D03*
X1584783D03*
X1594783D03*
X1653030Y5500D03*
X1663030D03*
X1623030D03*
X1633030D03*
X1643030D03*
X1668030D03*
X1658030D03*
X1648030D03*
X1638030D03*
X1628030D03*
X1664783Y1369303D03*
X1654783D03*
X1644783D03*
X1634783D03*
X1624783D03*
X1649783D03*
X1659783D03*
X1629783D03*
X1639783D03*
X1703030Y5500D03*
X1713030D03*
X1673030D03*
X1683030D03*
X1693030D03*
X1718030D03*
X1708030D03*
X1698030D03*
X1688030D03*
X1678030D03*
X1697261Y1004347D03*
X1692761D03*
Y999847D03*
Y995347D03*
X1697261D03*
Y999847D03*
X1714783Y1369303D03*
X1704783D03*
X1694783D03*
X1684783D03*
X1674783D03*
X1699783D03*
X1709783D03*
X1669783D03*
X1679783D03*
X1689783D03*
X1753030Y5500D03*
X1763030D03*
X1723030D03*
X1733030D03*
X1743030D03*
X1758030D03*
X1748030D03*
X1738030D03*
X1728030D03*
X1764783Y1369303D03*
X1754783D03*
X1744783D03*
X1734783D03*
X1724783D03*
X1749783D03*
X1759783D03*
X1719783D03*
X1729783D03*
X1739783D03*
X1778030Y5500D03*
X1793030D03*
X1803030D03*
X1813030D03*
X1808030D03*
X1798030D03*
X1783030D03*
X1788030D03*
X1773030D03*
X1768030D03*
X1783806Y989468D03*
X1804783Y1369303D03*
X1794783D03*
X1784783D03*
X1774783D03*
X1799783D03*
X1809783D03*
X1769783D03*
X1779783D03*
X1789783D03*
X1843030Y5500D03*
X1853030D03*
X1863030D03*
X1838030D03*
X1858030D03*
X1848030D03*
X1823030D03*
X1833030D03*
X1828030D03*
X1818030D03*
X1862652Y846508D03*
X1850263Y964540D03*
X1850370Y960239D03*
X1845870D03*
X1845763Y964540D03*
Y956040D03*
X1850263D03*
X1825741Y969210D03*
Y974210D03*
X1840683Y969318D03*
Y974318D03*
X1825744Y986011D03*
X1840578Y985885D03*
X1844863Y983125D03*
X1853863D03*
X1858363D03*
X1849363D03*
X1862863D03*
X1853863Y978125D03*
X1844863D03*
X1849363D03*
X1862863D03*
X1858363D03*
X1825744Y991011D03*
X1840578Y990885D03*
X1854783Y1369303D03*
X1844783D03*
X1834783D03*
X1824783D03*
X1814783D03*
X1849783D03*
X1859783D03*
X1819783D03*
X1829783D03*
X1839783D03*
X1878030Y5500D03*
X1883030D03*
X1873030D03*
X1868030D03*
X1909030D03*
X1888030D03*
X1873099Y817150D03*
X1878099D03*
X1873099Y821650D03*
X1878099D03*
X1873099Y826150D03*
X1878099D03*
X1877512Y831377D03*
X1882512D03*
X1865202Y831559D03*
X1873012Y831377D03*
X1878099Y812650D03*
X1873099D03*
X1878099Y808150D03*
X1873099D03*
X1878099Y803650D03*
X1873099D03*
X1878373Y846472D03*
X1883373D03*
X1867652Y846508D03*
X1867363Y983125D03*
Y978125D03*
X1904783Y1369303D03*
X1894783D03*
X1884783D03*
X1874783D03*
X1864783D03*
X1899783D03*
X1909783D03*
X1869783D03*
X1879783D03*
X1889783D03*
X1929343Y16525D03*
Y11525D03*
Y6525D03*
X1914030Y5500D03*
X1919030D03*
X1924030D03*
X1929343Y46525D03*
Y41525D03*
Y36525D03*
Y31525D03*
Y26525D03*
Y21525D03*
Y66525D03*
Y61525D03*
Y56525D03*
Y51525D03*
Y116525D03*
Y111525D03*
Y106525D03*
Y101525D03*
Y96525D03*
Y91525D03*
Y86525D03*
Y81525D03*
Y76525D03*
Y71525D03*
Y121525D03*
Y126525D03*
Y136525D03*
Y146525D03*
Y156525D03*
Y161525D03*
Y151525D03*
Y141525D03*
Y131525D03*
Y176525D03*
Y186525D03*
Y196525D03*
Y206525D03*
Y166525D03*
Y211525D03*
Y201525D03*
Y191525D03*
Y181525D03*
Y171525D03*
Y226525D03*
Y236525D03*
Y246525D03*
Y256525D03*
Y216525D03*
Y261525D03*
Y251525D03*
Y241525D03*
Y231525D03*
Y221525D03*
Y276525D03*
Y286525D03*
Y296525D03*
Y306525D03*
Y266525D03*
Y301525D03*
Y291525D03*
Y281525D03*
Y271525D03*
Y326525D03*
Y336525D03*
Y346525D03*
Y356525D03*
Y316525D03*
Y351525D03*
Y341525D03*
Y331525D03*
Y321525D03*
Y311525D03*
Y376525D03*
Y386525D03*
Y396525D03*
Y406525D03*
Y366525D03*
Y401525D03*
Y391525D03*
Y381525D03*
Y371525D03*
Y361525D03*
Y426525D03*
Y436525D03*
Y446525D03*
Y416525D03*
Y451525D03*
Y441525D03*
Y431525D03*
Y421525D03*
Y411525D03*
Y476525D03*
Y486525D03*
Y496525D03*
Y456525D03*
Y466525D03*
Y501525D03*
Y491525D03*
Y481525D03*
Y471525D03*
Y461525D03*
Y526525D03*
Y536525D03*
Y546525D03*
Y506525D03*
Y516525D03*
Y551525D03*
Y541525D03*
Y531525D03*
Y521525D03*
Y511525D03*
Y576525D03*
Y586525D03*
Y596525D03*
Y556525D03*
Y566525D03*
Y591525D03*
Y581525D03*
Y571525D03*
Y561525D03*
Y626525D03*
Y636525D03*
Y646525D03*
Y606525D03*
Y616525D03*
Y641525D03*
Y631525D03*
Y621525D03*
Y611525D03*
Y601525D03*
Y676525D03*
Y686525D03*
Y696525D03*
Y656525D03*
Y666525D03*
Y691525D03*
Y681525D03*
Y671525D03*
Y661525D03*
Y651525D03*
Y726525D03*
Y736525D03*
Y706525D03*
Y716525D03*
Y741525D03*
Y731525D03*
Y721525D03*
Y711525D03*
Y701525D03*
Y776525D03*
Y786525D03*
Y746525D03*
Y756525D03*
Y766525D03*
Y791525D03*
Y781525D03*
Y771525D03*
Y761525D03*
Y751525D03*
Y826525D03*
Y836525D03*
Y796525D03*
Y806525D03*
Y816525D03*
Y841525D03*
Y831525D03*
Y821525D03*
Y811525D03*
Y801525D03*
Y876525D03*
Y886525D03*
Y846525D03*
Y856525D03*
Y866525D03*
Y881525D03*
Y871525D03*
Y861525D03*
Y851525D03*
Y926525D03*
Y896525D03*
Y906525D03*
Y916525D03*
Y931525D03*
Y921525D03*
Y911525D03*
Y901525D03*
Y891525D03*
Y936525D03*
Y973863D03*
Y978863D03*
Y983863D03*
Y951525D03*
Y956525D03*
Y961525D03*
Y966525D03*
Y946525D03*
Y941525D03*
Y988863D03*
Y993863D03*
Y998863D03*
Y1003863D03*
Y1008863D03*
Y1033863D03*
Y1028863D03*
Y1023863D03*
Y1018863D03*
Y1013863D03*
Y1073863D03*
Y1083863D03*
Y1043863D03*
Y1053863D03*
Y1063863D03*
Y1078863D03*
Y1068863D03*
Y1058863D03*
Y1048863D03*
Y1038863D03*
Y1123863D03*
Y1093863D03*
Y1103863D03*
Y1113863D03*
Y1128863D03*
Y1118863D03*
Y1108863D03*
Y1098863D03*
Y1088863D03*
Y1173863D03*
Y1133863D03*
Y1143863D03*
Y1153863D03*
Y1163863D03*
Y1178863D03*
Y1168863D03*
Y1158863D03*
Y1148863D03*
Y1138863D03*
Y1223863D03*
Y1183863D03*
Y1193863D03*
Y1203863D03*
Y1213863D03*
Y1228863D03*
Y1218863D03*
Y1208863D03*
Y1198863D03*
Y1188863D03*
Y1273863D03*
Y1233863D03*
Y1243863D03*
Y1253863D03*
Y1263863D03*
Y1268863D03*
Y1258863D03*
Y1248863D03*
Y1238863D03*
Y1323863D03*
Y1283863D03*
Y1293863D03*
Y1303863D03*
Y1313863D03*
Y1318863D03*
Y1308863D03*
Y1298863D03*
Y1288863D03*
Y1278863D03*
Y1333863D03*
Y1343863D03*
Y1353863D03*
X1924783Y1369303D03*
X1914783D03*
X1919783D03*
X1929343Y1358863D03*
Y1348863D03*
Y1338863D03*
Y1328863D03*
Y1363863D03*
G54D21*
X72837Y177961D03*
Y630717D03*
Y1083473D03*
X140372Y736524D03*
X133063Y1006025D03*
X197049Y177961D03*
X199763Y594025D03*
X197449Y1083473D03*
X264739Y736268D03*
X337721Y121955D03*
X321362Y177961D03*
X321262Y630717D03*
Y1083473D03*
X365162Y92470D03*
X388796Y736196D03*
X389067Y1166330D03*
X445474Y177961D03*
Y630717D03*
X457173Y1072026D03*
X445573Y1104126D03*
X525579Y541581D03*
X512892Y736449D03*
X569687Y177961D03*
X575779Y516631D03*
X557279D03*
X594267Y530670D03*
X569687Y630717D03*
Y1083473D03*
X611910Y551674D03*
X637326Y736366D03*
X666142Y106519D03*
X693900Y177961D03*
Y1083473D03*
X752500Y1148300D03*
X877673Y861703D03*
X882400Y861668D03*
X876748Y1355107D03*
X876740Y1347014D03*
X882445Y1407597D03*
X877445D03*
X886792Y1407714D03*
X868500Y1435800D03*
X886500D03*
X877500D03*
X888600Y1482550D03*
X923600Y909000D03*
X928100D03*
X919100D03*
X932361Y959507D03*
X920607Y959382D03*
X936861Y959507D03*
X926100Y978500D03*
X930600D03*
X917100D03*
X929105Y1028560D03*
X920879Y1028703D03*
X932559Y1363584D03*
X936994Y1373148D03*
X932564Y1349912D03*
X926500Y1503000D03*
X942000D03*
X896365Y1516592D03*
X896335Y1525008D03*
X961500Y908300D03*
X966000D03*
X963900Y953700D03*
X950500Y979300D03*
X959500D03*
X946000D03*
X960400Y1024100D03*
X947125Y1372957D03*
X951872Y1361902D03*
X946300Y1503000D03*
X963488Y1517039D03*
X972413Y1545966D03*
X1039100Y905000D03*
X1020480Y904800D03*
X1015728D03*
X1023100Y956050D03*
X997694Y978140D03*
X1011194D03*
X993194D03*
X1017194Y1027240D03*
X1032500Y1070300D03*
X1037000D03*
X1023500D03*
X1035900Y1118100D03*
X1013400Y1140800D03*
X1004300D03*
X999700D03*
X1074400Y-77068D03*
X1043112Y-42008D03*
X1066225Y-47400D03*
X1046803Y872727D03*
X1042101Y877241D03*
X1043900Y905000D03*
X1053200D03*
X1073500Y1070300D03*
X1069000D03*
X1082500D03*
X1110500Y1070400D03*
X1119700D03*
X1124500D03*
X1128800Y1118500D03*
X1092200Y1119200D03*
X1176300Y292700D03*
X1180953Y292785D03*
X1176100Y274200D03*
X1176500Y1116800D03*
X1215547Y253315D03*
X1185588Y292750D03*
X1190200Y292700D03*
X1199000Y292300D03*
X1323521Y82755D03*
X1318821D03*
X1304563Y87558D03*
X1307500Y165961D03*
Y618717D03*
X1305100Y1071473D03*
X1354437Y81538D03*
X1337634Y130388D03*
X1421969Y517057D03*
X1413400Y567900D03*
X1431713Y165961D03*
X1470700Y525400D03*
X1435200Y518400D03*
X1448261Y518334D03*
X1456439Y518366D03*
X1447700Y572400D03*
X1474700D03*
X1431713Y618717D03*
Y1071473D03*
X1478700Y572400D03*
X1555925Y165961D03*
Y618717D03*
Y1071473D03*
X1585757Y126304D03*
X1602200Y1111200D03*
X1680138Y165961D03*
Y618717D03*
Y1071473D03*
X1804350Y165961D03*
Y618717D03*
X1774863Y1018025D03*
X1800750Y1071273D03*
X1855517Y161775D03*
X1843917Y193975D03*
X1855417Y614531D03*
X1843917Y646731D03*
X1840433Y1099941D03*
X1836431Y1144459D03*
X1868100Y1058800D03*
G54D30*
X68937Y254661D03*
X73437Y240161D03*
Y692917D03*
X68937Y707417D03*
Y1160173D03*
X73437Y1145673D03*
X79937Y254661D03*
X84437Y240161D03*
Y692917D03*
X79937Y707417D03*
Y1160173D03*
X84437Y1145673D03*
X204149Y254661D03*
X193149D03*
X197649Y240161D03*
X208649D03*
X197649Y692917D03*
X208649D03*
X193149Y707417D03*
X204149D03*
X193149Y1160173D03*
X204149D03*
X197649Y1145673D03*
X208649D03*
X328362Y254661D03*
X317362D03*
X321862Y240161D03*
X332862D03*
X321862Y692917D03*
X332862D03*
X317362Y707417D03*
X328362D03*
X317362Y1160173D03*
X328362D03*
X321862Y1145673D03*
X332862D03*
X452574Y254661D03*
X441574D03*
X446074Y240161D03*
X457074D03*
X446074Y692917D03*
X457074D03*
X441574Y707417D03*
X452574D03*
X456200Y1160200D03*
X467200D03*
X534874Y1145973D03*
X523874D03*
X576787Y254661D03*
X565787D03*
X570287Y240161D03*
X581287D03*
X570287Y692917D03*
X581287D03*
X565787Y707417D03*
X576787D03*
X565787Y1160173D03*
X576787D03*
X570287Y1145673D03*
X581287D03*
X701000Y254661D03*
X690000D03*
X694500Y240161D03*
Y692917D03*
X690000Y707417D03*
X701000D03*
X690000Y1160173D03*
X701000D03*
X694500Y1145673D03*
X705500Y240161D03*
Y692917D03*
Y1145673D03*
X1310500Y240661D03*
X1299500D03*
X1318775Y273366D03*
X1307775D03*
X1310500Y693417D03*
X1299500D03*
X1318834Y726182D03*
X1307834D03*
X1310500Y1146173D03*
X1299500D03*
X1318775Y1178761D03*
X1307775D03*
X1423713Y240661D03*
Y693417D03*
Y1146173D03*
X1434713Y240661D03*
X1443047Y273425D03*
X1432047D03*
X1434713Y693417D03*
X1443165Y726005D03*
X1432165D03*
X1442871Y1178820D03*
X1431871D03*
X1434713Y1146173D03*
X1558925Y240661D03*
X1547925D03*
X1567201Y273307D03*
X1556201D03*
X1558925Y693417D03*
X1547925D03*
X1567201Y726182D03*
X1556201D03*
X1558925Y1146173D03*
X1547925D03*
X1567259Y1179291D03*
X1556259D03*
X1683138Y240661D03*
X1672138D03*
X1691296Y273366D03*
X1680296D03*
X1683138Y693417D03*
X1672138D03*
X1691413Y726063D03*
X1680413D03*
X1683138Y1146173D03*
X1672138D03*
X1691590Y1178879D03*
X1680590D03*
X1807350Y240661D03*
X1796350D03*
X1804566Y273190D03*
X1807350Y693417D03*
X1796350D03*
X1806923Y725768D03*
X1807350Y1146173D03*
X1796350D03*
X1804743Y1178878D03*
X1860669Y254661D03*
X1815566Y273190D03*
X1817923Y725768D03*
X1857200Y707200D03*
X1815743Y1178878D03*
X1871669Y254661D03*
X1865169Y240161D03*
X1876169D03*
X1865169Y692917D03*
X1876169D03*
X1868200Y707200D03*
X1865548Y1126458D03*
X1876548D03*
X1875284Y1160157D03*
X1886284D03*
G54D12*
X22947Y674933D03*
X23314Y700284D03*
X22920Y1127900D03*
X22894Y1153251D03*
X26822Y682433D03*
X30697Y674933D03*
X27189Y707784D03*
X31064Y700284D03*
X30670Y1127900D03*
X26795Y1135400D03*
X26769Y1160751D03*
X30644Y1153251D03*
X149826Y732591D03*
X145951Y725091D03*
X153701D03*
X145955Y740011D03*
X153705D03*
X149830Y747511D03*
X149841Y1177842D03*
X145966Y1170342D03*
X153716D03*
X150001Y1200224D03*
X146126Y1192724D03*
X153876D03*
X274093Y732335D03*
X270218Y724835D03*
X277968D03*
X270222Y739755D03*
X277972D03*
X274097Y747255D03*
X274055Y1177842D03*
X270180Y1170342D03*
X277930D03*
X274215Y1200224D03*
X270340Y1192724D03*
X278090D03*
X398250Y732263D03*
X394375Y724763D03*
X402125D03*
X394379Y739683D03*
X402129D03*
X398254Y747183D03*
X398281Y1179045D03*
X394406Y1171545D03*
X402156D03*
X398386Y1200224D03*
X394511Y1192724D03*
X402261D03*
X522346Y732516D03*
X518471Y725016D03*
X526221D03*
X518475Y739936D03*
X526225D03*
X522350Y747436D03*
X522648Y1180116D03*
X518773Y1172616D03*
X526523D03*
X522513Y1200182D03*
X518638Y1192682D03*
X526388D03*
X646780Y732433D03*
X642905Y724933D03*
X650655D03*
X642909Y739853D03*
X650659D03*
X646784Y747353D03*
X646864Y1179909D03*
X642989Y1172409D03*
X650739D03*
X646769Y1200140D03*
X642894Y1192640D03*
X650644D03*
X934960Y949195D03*
X931085Y941695D03*
X938835D03*
X1225845Y1160891D03*
X1221970Y1153391D03*
X1229720D03*
X1239945Y1160864D03*
X1236070Y1153364D03*
X1243820D03*
X1357711Y1131655D03*
X1365461D03*
X1361586Y1139155D03*
X1360794Y1160724D03*
X1356919Y1153224D03*
X1364669D03*
X1481346Y1126841D03*
X1489096D03*
X1485221Y1134341D03*
X1485468Y1160808D03*
X1481593Y1153308D03*
X1489343D03*
X1620052Y1114449D03*
X1619446Y1138567D03*
X1623927Y1121949D03*
X1627802Y1114449D03*
X1623321Y1146067D03*
X1627196Y1138567D03*
X1728978Y1127935D03*
X1736728D03*
X1732853Y1135435D03*
X1732996Y1160608D03*
X1729121Y1153108D03*
X1736871D03*
X1860667Y1153308D03*
X1850477Y1160786D03*
X1846602Y1153286D03*
X1854352D03*
X1864542Y1160808D03*
X1868417Y1153308D03*
G54D105*
X1104804Y1588583D03*
X1123032D03*
X1104804Y1601181D03*
X1123032D03*
G54D22*
X72837Y181361D03*
Y634117D03*
Y1086873D03*
X140372Y739924D03*
X133063Y1009425D03*
X197049Y181361D03*
X199763Y597425D03*
X197449Y1086873D03*
X264739Y739668D03*
X337721Y125355D03*
X321362Y181361D03*
X321262Y634117D03*
Y1086873D03*
X365162Y95870D03*
X388796Y739596D03*
X389067Y1169730D03*
X445474Y181361D03*
Y634117D03*
X457173Y1075426D03*
X445573Y1107526D03*
X525579Y544981D03*
X512892Y739849D03*
X569687Y181361D03*
X575779Y520031D03*
X557279D03*
X594267Y534070D03*
X569687Y634117D03*
Y1086873D03*
X611910Y555074D03*
X637326Y739766D03*
X666142Y109919D03*
X693900Y181361D03*
Y1086873D03*
X752500Y1151700D03*
X877673Y865103D03*
X882400Y865068D03*
X876748Y1358507D03*
X876740Y1350414D03*
X882445Y1410997D03*
X877445D03*
X886792Y1411114D03*
X868500Y1439200D03*
X886500D03*
X877500D03*
X888600Y1485950D03*
X923600Y912400D03*
X928100D03*
X919100D03*
X932361Y962907D03*
X920607Y962782D03*
X936861Y962907D03*
X926100Y981900D03*
X930600D03*
X917100D03*
X929105Y1031960D03*
X920879Y1032103D03*
X932559Y1366984D03*
X932564Y1353312D03*
X936994Y1376548D03*
X926500Y1506400D03*
X942000D03*
X896335Y1528408D03*
X896365Y1519992D03*
X961500Y911700D03*
X966000D03*
X963900Y957100D03*
X950500Y982700D03*
X959500D03*
X946000D03*
X960400Y1027500D03*
X951872Y1365302D03*
X947125Y1376357D03*
X946300Y1506400D03*
X972413Y1549366D03*
X963488Y1520439D03*
X1039100Y908400D03*
X1020480Y908200D03*
X1015728D03*
X1023100Y959450D03*
X997694Y981540D03*
X1011194D03*
X993194D03*
X1017194Y1030640D03*
X1032500Y1073700D03*
X1037000D03*
X1023500D03*
X1035900Y1121500D03*
X1013400Y1144200D03*
X1004300D03*
X999700D03*
X1043112Y-38608D03*
X1066225Y-44000D03*
X1074400Y-73668D03*
X1046803Y876127D03*
X1042101Y880641D03*
X1043900Y908400D03*
X1053200D03*
X1073500Y1073700D03*
X1069000D03*
X1082500D03*
X1110500Y1073800D03*
X1119700D03*
X1124500D03*
X1128800Y1121900D03*
X1092200Y1122600D03*
X1176300Y296100D03*
X1180953Y296185D03*
X1176100Y277600D03*
X1176500Y1120200D03*
X1215547Y256715D03*
X1185588Y296150D03*
X1190200Y296100D03*
X1199000Y295700D03*
X1323521Y86155D03*
X1318821D03*
X1304563Y90958D03*
X1307500Y169361D03*
Y622117D03*
X1305100Y1074873D03*
X1354437Y84938D03*
X1337634Y133788D03*
X1421969Y520457D03*
X1413400Y571300D03*
X1431713Y169361D03*
X1470700Y528800D03*
X1435200Y521800D03*
X1448261Y521734D03*
X1456439Y521766D03*
X1447700Y575800D03*
X1474700D03*
X1431713Y622117D03*
Y1074873D03*
X1478700Y575800D03*
X1555925Y169361D03*
Y622117D03*
Y1074873D03*
X1585757Y129704D03*
X1602200Y1114600D03*
X1680138Y169361D03*
Y622117D03*
Y1074873D03*
X1804350Y169361D03*
Y622117D03*
X1774863Y1021425D03*
X1800750Y1074673D03*
X1855517Y165175D03*
X1843917Y197375D03*
X1855417Y617931D03*
X1843917Y650131D03*
X1840433Y1103341D03*
X1836431Y1147859D03*
X1868100Y1062200D03*
G54D31*
X61737Y254661D03*
X54137D03*
X61737Y707417D03*
X54137D03*
X61737Y1160173D03*
X54137D03*
X117994Y966075D03*
X103200Y975500D03*
X110800D03*
X103200Y967900D03*
X110800D03*
X169900Y563500D03*
Y555900D03*
X125594Y966075D03*
X185949Y254661D03*
X178349D03*
X184694Y554075D03*
X192294D03*
X177500Y563500D03*
Y555900D03*
X185949Y707417D03*
X178349D03*
X185949Y1160173D03*
X178349D03*
X310162Y254661D03*
X302562D03*
X310162Y707417D03*
X302562D03*
X310162Y1160173D03*
X302562D03*
X434374Y254661D03*
X426774D03*
X434374Y707417D03*
X426774D03*
X449338Y1160696D03*
X441738D03*
X550987Y254661D03*
Y707417D03*
Y1160173D03*
X558587Y254661D03*
X581036Y506682D03*
X588636D03*
X558587Y707417D03*
Y1160173D03*
X648465Y577467D03*
X682800Y254661D03*
X675200D03*
X656065Y577467D03*
X682800Y707417D03*
X675200D03*
X682800Y1160173D03*
X675200D03*
X826362Y43947D03*
X833962D03*
X861930Y43376D03*
X869530D03*
X861536Y75972D03*
X869136D03*
X1180068Y716700D03*
X1197068Y58168D03*
X1189468D03*
X1187668Y716700D03*
X1448662Y588301D03*
X1441062D03*
X1759794Y978075D03*
X1745000Y987500D03*
X1752600D03*
X1745000Y979900D03*
X1752600D03*
X1767394Y978075D03*
X1853469Y254661D03*
X1845869D03*
X1849876Y707417D03*
X1842276D03*
G54D106*
X1181145Y274100D03*
X1183115D03*
Y264900D03*
X1181145D03*
X1185085Y274100D03*
X1187055D03*
Y264900D03*
X1185085D03*
G54D40*
X80019Y51968D03*
X127263Y20472D03*
X631200Y51968D03*
X678444Y20472D03*
X1250689Y51969D03*
X1297933Y20472D03*
X1801870Y51969D03*
X1849114Y20472D03*
G54D13*
X21999Y667471D03*
X22600Y693100D03*
X21626Y1120900D03*
X22100Y1146200D03*
X25000Y1209100D03*
X60187Y194161D03*
X67987Y199261D03*
X68937Y262161D03*
X72049Y424200D03*
X68109Y453300D03*
X43100Y464100D03*
X57963Y457439D03*
X47607Y520462D03*
X61834Y520466D03*
X60187Y646917D03*
X67987Y651900D03*
X68937Y714917D03*
X33900Y764200D03*
X28400Y763600D03*
X72049Y923100D03*
X68109Y932900D03*
X60187Y1099673D03*
X68100Y1104973D03*
X68937Y1167673D03*
X30000Y1206100D03*
X52600Y1201300D03*
X48219Y1196721D03*
X77237Y181411D03*
X81437Y177911D03*
X88300Y186300D03*
X82437Y260661D03*
X79200Y233800D03*
X77237Y634167D03*
X81437Y630667D03*
X87819Y638950D03*
X85146Y625491D03*
X79000Y686500D03*
X82437Y713417D03*
X108647Y980933D03*
X101403Y981195D03*
X96563Y969225D03*
X110363Y1003825D03*
X117063Y1006725D03*
X108063Y988125D03*
X102113Y998225D03*
X81437Y1083423D03*
X77237Y1086923D03*
X88787Y1091673D03*
X82437Y1166173D03*
X78700Y1139500D03*
X139187Y250161D03*
X145437Y261100D03*
X167992Y400500D03*
X168813Y586225D03*
X168103Y569195D03*
X163263Y557225D03*
X139187Y702917D03*
X150253Y718842D03*
X140364Y745281D03*
X145437Y713700D03*
X159600Y758942D03*
X149830Y762815D03*
X137163Y987125D03*
X132175Y979825D03*
X133663Y973825D03*
X131563Y966735D03*
X145363Y997741D03*
X128063Y1006725D03*
X150869Y1163222D03*
X139187Y1155673D03*
X140166Y1214922D03*
X147538Y1213917D03*
X144264Y1186512D03*
X165490Y1217508D03*
X154473Y1213919D03*
X201449Y181411D03*
X184399Y194161D03*
X192199Y199061D03*
X205649Y177911D03*
X212999Y186161D03*
X206649Y260661D03*
X203400Y234000D03*
X193149Y262161D03*
X196261Y397500D03*
X192321Y406000D03*
X182217Y399500D03*
X171861Y520420D03*
X186088Y520424D03*
X210263Y550725D03*
X177063Y591825D03*
X212063Y585741D03*
X194763Y594725D03*
X183763D03*
X174763Y576125D03*
X203863Y575125D03*
X198263Y554735D03*
X198004Y567809D03*
X200363Y561825D03*
X202174Y625523D03*
X196360Y638400D03*
X207409Y625539D03*
X212999Y628417D03*
X203600Y686800D03*
X198000Y650000D03*
X206649Y713417D03*
X193149Y714917D03*
X202534Y917700D03*
X206200Y925200D03*
X208700Y1023450D03*
X205649Y1083423D03*
X201449Y1086923D03*
X183793Y1104177D03*
X194100Y1101800D03*
X212999Y1091673D03*
X206649Y1166173D03*
X193149Y1167673D03*
X203100Y1139500D03*
X263399Y250161D03*
X232400Y569725D03*
X263399Y702917D03*
X264731Y745025D03*
X263399Y1155673D03*
X311000Y76700D03*
X308612Y194161D03*
X269649Y260800D03*
X292153Y491834D03*
X306388Y491797D03*
X296032Y520420D03*
X310259Y520424D03*
X308612Y646917D03*
X268071Y713929D03*
X274520Y718586D03*
X283516Y768434D03*
X274097Y762119D03*
X308612Y1099673D03*
X275087Y1163231D03*
X268478Y1186512D03*
X284954Y1257055D03*
X280888Y1249308D03*
X303376Y1248708D03*
X306015Y1256575D03*
X353894Y66695D03*
X335766Y74334D03*
X322965Y77565D03*
X329529Y77300D03*
X329961Y115700D03*
X333741Y117531D03*
X319329Y117277D03*
X340201Y118481D03*
X325662Y181411D03*
X316412Y199161D03*
X329862Y177911D03*
X337212Y186161D03*
X330862Y260661D03*
X327600Y234000D03*
X317362Y262161D03*
X320925Y491367D03*
X315925Y491578D03*
X325662Y634167D03*
X329862Y630667D03*
X336409Y639049D03*
X333682Y625711D03*
X328000Y686700D03*
X316412Y651917D03*
X330862Y713417D03*
X317362Y714917D03*
X320925Y943284D03*
X315925Y943495D03*
X329862Y1083423D03*
X325662Y1086923D03*
X317811Y1102937D03*
X337312Y1091773D03*
X330862Y1166173D03*
X317362Y1167673D03*
X327600Y1139400D03*
X371619Y84720D03*
X370390Y95920D03*
X387612Y251061D03*
X391986Y262414D03*
X387612Y702917D03*
X393862Y714500D03*
X398677Y718514D03*
X388788Y744953D03*
X407714Y756056D03*
X398254Y757066D03*
X387612Y1155673D03*
X393698Y1166123D03*
X393193Y1220531D03*
X391827Y1214891D03*
X392977Y1185945D03*
X403487Y1213549D03*
X449874Y181411D03*
X432824Y194161D03*
X440624Y199100D03*
X454074Y177911D03*
X455074Y260661D03*
X451800Y234000D03*
X441574Y262161D03*
X445138Y492299D03*
X440138Y492173D03*
X416303Y491797D03*
X430538Y491760D03*
X420182Y520383D03*
X434409Y520387D03*
X449874Y634167D03*
X432824Y646917D03*
X454074Y630667D03*
X457853Y625956D03*
X452000Y686600D03*
X441600Y650800D03*
X455074Y713417D03*
X441574Y714917D03*
X445138Y943284D03*
X440138Y943495D03*
X443923Y1082726D03*
X452173Y1075476D03*
X447423Y1086926D03*
X453423Y1108600D03*
X456174Y1167573D03*
X415430Y1216989D03*
X461424Y186161D03*
X460521Y638901D03*
X511824Y250161D03*
X518074Y260500D03*
X539350Y491729D03*
X534350Y491940D03*
X510621Y491834D03*
X524856Y491797D03*
X550161Y544768D03*
X549279Y524831D03*
X554889Y550331D03*
X521191Y545078D03*
X514500Y520420D03*
X528727Y520424D03*
X553279Y530931D03*
Y537910D03*
X536900Y528500D03*
X536891Y532831D03*
X554055Y576466D03*
X552379Y566531D03*
X536979Y553219D03*
X513729Y557675D03*
X511824Y702917D03*
X515025Y715075D03*
X522773Y718767D03*
X512884Y745206D03*
X531810Y755383D03*
X522350Y756393D03*
X509300Y1121500D03*
X514000Y1139900D03*
X514274Y1161673D03*
X518975Y1167110D03*
X517342Y1185651D03*
X544486Y1266486D03*
X534733Y1252634D03*
X547100Y1232500D03*
X554772Y1250785D03*
X574087Y181411D03*
X557037Y194161D03*
X566160Y197579D03*
X578287Y177911D03*
X585637Y186161D03*
X579287Y260661D03*
X576700Y234000D03*
X565787Y262161D03*
X575607Y499947D03*
X588026Y526957D03*
X594795Y504965D03*
X569347Y524499D03*
X587279Y547831D03*
X575779Y524831D03*
X588978Y534615D03*
X564388Y526640D03*
X599247Y525694D03*
X596414Y538329D03*
Y543329D03*
X560500Y558600D03*
X601979Y559456D03*
X593779Y556274D03*
X576029Y561181D03*
X568029Y560831D03*
X586279Y560331D03*
X562279Y565331D03*
X580053Y559080D03*
X574087Y634167D03*
X557037Y646917D03*
X578287Y630667D03*
X585637Y638917D03*
X576300Y686800D03*
X564937Y651917D03*
X579287Y713417D03*
X565787Y714917D03*
X569350Y945784D03*
X564350Y945995D03*
X578287Y1083423D03*
X574087Y1086923D03*
X557037Y1099673D03*
X564837Y1104800D03*
X585637Y1091673D03*
X579000Y1166500D03*
X565787Y1167673D03*
X576000Y1139700D03*
X616903Y107633D03*
X636037Y250161D03*
X642287Y262200D03*
X627863Y517621D03*
X642344Y516870D03*
X606884Y525791D03*
X642152Y578952D03*
X636037Y702917D03*
X642287Y714800D03*
X647207Y718684D03*
X637318Y745123D03*
X646784Y756310D03*
X636037Y1155673D03*
X647716Y1165672D03*
X638776Y1214234D03*
X641383Y1186238D03*
X661638Y109969D03*
X685711Y101931D03*
X698300Y181411D03*
X681250Y194161D03*
X690166Y198044D03*
X699900Y233700D03*
X690000Y262161D03*
X693112Y382100D03*
X689172Y380276D03*
X693112Y361401D03*
X689172Y362876D03*
X699025Y636023D03*
X679213Y612355D03*
X690213Y603973D03*
X701000Y686700D03*
X689758Y649790D03*
X689050Y669146D03*
X690000Y714917D03*
X656244Y755300D03*
X689172Y928400D03*
X693112Y940100D03*
X698300Y1086923D03*
X680400Y1105800D03*
X691400Y1101900D03*
X690000Y1167673D03*
X700100Y1139500D03*
X658241Y1228338D03*
X658303Y1216330D03*
X679907Y1232607D03*
X702500Y177911D03*
X709850Y186161D03*
X703500Y260661D03*
X704260Y635957D03*
X709850Y638917D03*
X703500Y713417D03*
X737984Y861689D03*
X747383Y924689D03*
X702500Y1083423D03*
X709850Y1091673D03*
X703500Y1166173D03*
X758000Y223500D03*
X753893Y912630D03*
X760250Y1154000D03*
X779535Y1180469D03*
X792263Y1178661D03*
Y1174461D03*
Y1170261D03*
X784544Y1210178D03*
Y1205978D03*
X779535Y1193469D03*
Y1189269D03*
Y1184669D03*
X797177Y1189537D03*
X797225Y1185337D03*
X792263Y1182861D03*
X882900Y359100D03*
X883200Y378495D03*
X882400Y445462D03*
X882500Y450200D03*
Y454900D03*
X870179D03*
X870389Y445462D03*
X870221Y450200D03*
X882600Y459562D03*
X882700Y464505D03*
X870263Y459562D03*
X883900Y542405D03*
X884182Y820251D03*
X879519Y821655D03*
X874623Y822631D03*
X881203Y852900D03*
X876900D03*
X885873Y852800D03*
X888643Y1356566D03*
X889223Y1350339D03*
X885754Y1375500D03*
X885608Y1379698D03*
X877500Y1443500D03*
X881901Y1443300D03*
X871325Y1443125D03*
X888000Y1478800D03*
X883647Y1478447D03*
X879341Y1478200D03*
X882572Y1492349D03*
X879321Y1489661D03*
X855535Y1498705D03*
X855523Y1504750D03*
X888390Y1534018D03*
X855899Y1529934D03*
X867500Y1519500D03*
X915654Y916254D03*
X921100Y916100D03*
X928100Y916200D03*
X923600Y905000D03*
X928100Y905300D03*
X901540Y916200D03*
X904100Y912860D03*
X933524Y916449D03*
X923985Y954185D03*
X918577Y955523D03*
X929960Y954810D03*
X918220Y985720D03*
X923100Y985700D03*
X927460Y985574D03*
X927917Y974344D03*
X934343Y978450D03*
X912994Y967848D03*
X910594Y955106D03*
X906600Y985800D03*
X908094Y965295D03*
X905506Y958415D03*
X902866Y964401D03*
X900400Y960942D03*
X901480Y985800D03*
X926513Y1023713D03*
X920500Y1024400D03*
X932316Y1023966D03*
X942893Y1001345D03*
X918430Y1040930D03*
X919778Y1047278D03*
X919400Y1056000D03*
X914100Y1056200D03*
X910387Y1051177D03*
X904875Y1046590D03*
X924200Y1371800D03*
X924436Y1367064D03*
X924400Y1362000D03*
X925313Y1356403D03*
X924300Y1376100D03*
X938000Y1511000D03*
X918500Y1510200D03*
X898378Y1478800D03*
X924000Y1518200D03*
X929000Y1544700D03*
X921500Y1544200D03*
X924300Y1530184D03*
X937250Y1547200D03*
X924110Y1536700D03*
X931500Y1548200D03*
X923400Y1524279D03*
X900248Y1521048D03*
X904900Y1534500D03*
X958200Y915800D03*
X963066Y915830D03*
X953320Y915800D03*
X961100Y949800D03*
X956800Y949900D03*
X950400Y949800D03*
X951700Y986600D03*
X956300D03*
X947400Y986458D03*
X981580Y953300D03*
X979020Y949700D03*
X976460Y953300D03*
X973900Y949800D03*
X971340Y953300D03*
X968780Y949800D03*
X944617Y975530D03*
X945790Y945819D03*
X956100Y1020300D03*
X951800D03*
X946800Y1020200D03*
X981500Y1179000D03*
X968800Y1158500D03*
X957346Y1516124D03*
X964419Y1509261D03*
X946300Y1511200D03*
X967998Y1512551D03*
X988573Y1513673D03*
X971069Y1495465D03*
X972158Y1542266D03*
X961008Y1546961D03*
X959987Y1541339D03*
X945250Y1547450D03*
X956597Y1533926D03*
X955236Y1546187D03*
X958199Y1520984D03*
X948750Y1545050D03*
X998045Y-90000D03*
X1006660Y-81200D03*
X1010800Y-77400D03*
X1004100Y-47369D03*
X1029900Y-75400D03*
X1004100Y-65700D03*
X1039560Y-45900D03*
X1038808Y-67700D03*
X1019100Y-43996D03*
Y-62000D03*
X1010380Y-20480D03*
X1011125Y-15559D03*
X1005981Y58902D03*
X1004000Y54400D03*
X1005400Y63780D03*
X1006815Y545207D03*
X1006400Y554532D03*
X1035958Y838664D03*
X1037400Y868600D03*
X1033600Y912400D03*
X1019221Y913481D03*
X1025400Y912800D03*
X1012750Y926499D03*
X1000174Y986100D03*
X1006694D03*
X1023100Y951000D03*
X994900Y986000D03*
X1009200Y1020500D03*
X1003000Y1023000D03*
X998439Y1023100D03*
X1029339Y1077911D03*
X1034069Y1077881D03*
X1024500Y1077800D03*
X1031400Y1112664D03*
X1026900Y1114107D03*
X1022400Y1114181D03*
X1026900Y1125640D03*
X1022400Y1125311D03*
X998208Y1148628D03*
X1004500Y1148300D03*
X1011497Y1148303D03*
X1009500Y1180377D03*
X1014500Y1180413D03*
X1004500Y1180370D03*
X1038000Y1324216D03*
X1038200Y1337616D03*
X1038400Y1342668D03*
X1038200Y1330916D03*
X1018483Y1474093D03*
X1075100Y-86200D03*
X1049500Y-73200D03*
X1062073Y-51100D03*
X1062400Y-72800D03*
X1074400Y-50694D03*
Y-69174D03*
X1073400Y22405D03*
X1073598Y79465D03*
X1053774Y429753D03*
X1053721Y434409D03*
X1047853Y446600D03*
X1053700Y557053D03*
X1049301Y835703D03*
X1046937Y829163D03*
X1042123Y868400D03*
X1083633Y864110D03*
X1046803Y868900D03*
X1042155Y912845D03*
X1051573Y912477D03*
X1083633Y902332D03*
X1074292Y1077704D03*
X1078534Y1077715D03*
X1069870Y1077770D03*
X1086842Y1114342D03*
X1079000Y1115489D03*
X1074500Y1115393D03*
X1041975Y1349992D03*
X1042039Y1354526D03*
X1074283Y1474093D03*
X1046283D03*
X1070400Y1521000D03*
X1105400Y-91100D03*
X1112600Y-94000D03*
X1089300Y-82962D03*
X1094300Y-84700D03*
X1089300Y-64555D03*
X1111778Y-60293D03*
X1107362Y-59500D03*
X1096500Y-53500D03*
X1120179Y1078250D03*
X1125362Y1078488D03*
X1115520Y1078475D03*
X1127100Y1113738D03*
X1122500Y1113770D03*
X1118000D03*
X1136007Y1114387D03*
X1172375Y101360D03*
X1171552Y96794D03*
X1185100Y245100D03*
X1185588Y301468D03*
X1180953Y303520D03*
X1176272Y301668D03*
X1180953Y288600D03*
X1185588Y288981D03*
X1182411Y317764D03*
X1178081Y329765D03*
X1148997Y1097672D03*
X1148830Y1091117D03*
X1145936Y1113107D03*
X1142020Y1114701D03*
X1138679Y1117874D03*
X1176500Y1127000D03*
X1223600Y241100D03*
X1190882Y255782D03*
X1190200Y301168D03*
X1220200Y268800D03*
X1190200Y288892D03*
X1192600Y277700D03*
X1188900Y281300D03*
X1192600Y273400D03*
X1189924Y314076D03*
X1188400Y1029031D03*
X1189900Y1033731D03*
X1211205Y1174705D03*
X1220723Y1146560D03*
X1216205Y1182451D03*
X1256500Y250161D03*
X1249000Y227700D03*
X1250500Y262600D03*
X1261500Y451500D03*
X1256500Y465200D03*
X1239758Y489880D03*
X1250660Y478500D03*
X1244910Y513555D03*
X1259426Y513463D03*
X1254500Y702917D03*
X1250660Y714960D03*
X1268742Y922198D03*
X1263742Y938298D03*
X1240222Y911913D03*
X1254331Y935742D03*
X1245251Y965973D03*
X1259600Y965700D03*
X1254750Y1155423D03*
X1251053Y1168353D03*
X1234995Y1146053D03*
X1242718Y1190900D03*
X1238778Y1222200D03*
X1304563Y96258D03*
X1323181Y89965D03*
X1328161Y90500D03*
X1299569Y96258D03*
X1317900Y90500D03*
X1327307Y124489D03*
X1319807Y125683D03*
X1317445Y120920D03*
X1317000Y178161D03*
X1308250Y186200D03*
X1324500Y194661D03*
X1317000Y169411D03*
X1326300Y165911D03*
X1310500Y247161D03*
X1310501Y279736D03*
X1317000Y630917D03*
X1302500Y642417D03*
X1324500Y647417D03*
X1317000Y622167D03*
X1326423Y618667D03*
X1310882Y732348D03*
X1310500Y699917D03*
X1317000Y1083673D03*
X1313400Y1074923D03*
X1302500Y1095173D03*
X1324500Y1100173D03*
X1310500Y1152673D03*
X1310494Y1184880D03*
X1336516Y87410D03*
X1337176Y78470D03*
X1340961Y82656D03*
X1343521Y89403D03*
X1348641Y87218D03*
X1331759Y80400D03*
X1333281Y90526D03*
X1349931Y134433D03*
X1331365Y125601D03*
X1351008Y124582D03*
X1343170Y125197D03*
X1336500Y194661D03*
X1334534Y274847D03*
X1374713Y263900D03*
X1366931Y402900D03*
X1362991Y429900D03*
X1347982Y482100D03*
X1356542Y458900D03*
X1341262Y513426D03*
X1355778Y513334D03*
X1368165Y542402D03*
X1361500Y567500D03*
X1369300Y578700D03*
X1336500Y647417D03*
X1378713Y702917D03*
X1334385Y726575D03*
X1374839Y715539D03*
X1362991Y888400D03*
X1366931Y921200D03*
X1345800Y924700D03*
X1354301Y935405D03*
X1343677Y965649D03*
X1358581Y966602D03*
X1336500Y1100173D03*
X1356639Y1123408D03*
X1378963Y1155600D03*
X1375887Y1169387D03*
X1355100Y1147400D03*
X1334232Y1181463D03*
X1346321Y1182700D03*
X1351321Y1211900D03*
X1366931Y1198700D03*
X1362991Y1254400D03*
X1380713Y251400D03*
X1402872Y535918D03*
X1426713Y642417D03*
Y1095173D03*
X1441213Y178161D03*
X1460713Y194661D03*
X1432463Y186623D03*
X1448713Y194661D03*
X1441213Y169411D03*
X1450700Y165937D03*
X1434713Y247161D03*
X1434890Y279853D03*
X1458098Y274316D03*
X1472194Y448500D03*
X1463085Y494974D03*
X1462848Y512169D03*
X1467000Y533700D03*
X1475600Y525900D03*
X1440400Y537300D03*
X1432800Y535300D03*
X1452584Y530090D03*
X1459950Y531600D03*
X1440700Y544600D03*
X1441700Y532100D03*
X1473090Y542100D03*
X1465700Y527100D03*
X1449614Y533651D03*
X1430431Y549130D03*
X1444000Y567000D03*
X1434414Y580369D03*
X1459200Y568200D03*
X1452200Y567600D03*
X1439000Y558000D03*
X1463521Y567421D03*
X1474700Y561500D03*
Y554521D03*
X1433200Y571600D03*
X1428200Y562850D03*
X1430431Y554130D03*
X1451686Y594814D03*
X1441213Y630917D03*
X1460713Y647417D03*
X1448713D03*
X1441213Y622167D03*
X1451016Y618667D03*
X1435496Y732268D03*
X1458283Y728459D03*
X1434713Y699917D03*
X1466036Y937510D03*
X1467889Y965707D03*
X1441213Y1083673D03*
Y1074923D03*
X1446213Y1066700D03*
X1460713Y1100173D03*
X1448713D03*
X1458334Y1180299D03*
X1434713Y1152673D03*
X1434536Y1185247D03*
X1503025Y250061D03*
X1497025Y273400D03*
X1491143Y420100D03*
X1487203Y448300D03*
X1481938Y493921D03*
X1477766Y479986D03*
X1477818Y547663D03*
X1492700Y539112D03*
X1512940Y533903D03*
X1478700Y567600D03*
X1502925Y702917D03*
X1498349Y715749D03*
X1491143Y863600D03*
X1487203Y887900D03*
X1484054Y911900D03*
X1482793Y966760D03*
X1479828Y1118016D03*
X1504700Y1156926D03*
X1500838Y1167938D03*
X1480600Y1144400D03*
X1491143Y1211600D03*
X1476175Y1265600D03*
X1481175Y1251700D03*
X1487203Y1234300D03*
X1565425Y178161D03*
X1556675Y186000D03*
X1565425Y169411D03*
X1558925Y247161D03*
X1559257Y279526D03*
X1565425Y630917D03*
X1551675Y640424D03*
X1565425Y622167D03*
X1567925Y649417D03*
X1559129Y732414D03*
X1558925Y699917D03*
X1565425Y1083673D03*
Y1074923D03*
X1570425Y1067600D03*
X1549425Y1092973D03*
X1558925Y1152673D03*
X1558141Y1185570D03*
X1565173Y1185730D03*
X1589100Y146241D03*
X1585757Y121382D03*
X1584925Y194661D03*
X1572925D03*
X1575479Y165911D03*
X1582965Y274048D03*
X1615356Y487800D03*
X1611416Y465200D03*
X1596407Y472700D03*
X1601101Y464367D03*
X1592144Y513510D03*
X1606660Y513418D03*
X1575057Y618667D03*
X1578976Y670497D03*
X1582690Y727290D03*
X1615356Y885149D03*
X1611416Y877400D03*
X1592128Y938753D03*
X1604967Y905900D03*
X1592102Y965633D03*
X1606800Y965889D03*
X1594025Y1093873D03*
X1582025D03*
X1619308Y1107701D03*
X1605083Y1217917D03*
X1615900Y1200200D03*
X1619940Y1225400D03*
X1615356Y1256600D03*
X1628738Y250061D03*
X1622738Y260500D03*
X1627138Y702917D03*
X1621138Y714900D03*
X1623034Y1132351D03*
X1689638Y178161D03*
X1709138Y194661D03*
X1680888Y186300D03*
X1697138Y194661D03*
X1689638Y169411D03*
X1699692Y165911D03*
X1683138Y247161D03*
X1682961Y280030D03*
X1706641Y275966D03*
X1716609Y513257D03*
X1689638Y630917D03*
X1709138Y647417D03*
X1675138Y642417D03*
X1697138Y647417D03*
X1689638Y622167D03*
X1699788Y618667D03*
X1683708Y732526D03*
X1706680Y727755D03*
X1683138Y699917D03*
X1689638Y1083673D03*
Y1074923D03*
X1694638Y1067600D03*
X1709138Y1100173D03*
X1675138Y1095173D03*
X1697138Y1100173D03*
X1683138Y1152673D03*
X1682961Y1185542D03*
X1706935Y1180888D03*
X1753550Y250061D03*
X1747550Y261100D03*
X1729179Y393700D03*
X1739568Y453500D03*
X1723619Y436700D03*
X1735628Y476630D03*
X1731125Y513165D03*
X1755459Y711160D03*
X1739568Y852900D03*
X1735628Y883800D03*
X1752000Y901047D03*
X1749145Y918827D03*
X1749242Y970095D03*
X1764356Y970161D03*
X1749573Y939015D03*
X1738363Y981225D03*
X1752163Y1015825D03*
X1758863Y1018725D03*
X1749863Y1000125D03*
X1743913Y1010225D03*
X1737241Y997843D03*
X1727481Y1120480D03*
X1751600Y1155523D03*
X1746700Y1169200D03*
X1727463Y1145781D03*
X1739568Y1209300D03*
X1735628Y1226800D03*
X1718117Y1274820D03*
X1723117Y1266400D03*
X1813850Y178161D03*
X1804897Y187050D03*
X1813850Y169411D03*
X1807350Y247161D03*
X1807880Y279499D03*
X1813850Y630917D03*
X1799350Y642417D03*
X1813850Y622167D03*
X1808526Y731698D03*
X1807350Y699917D03*
X1777666Y932748D03*
X1782666Y939436D03*
X1794767Y964624D03*
X1811581Y965390D03*
X1783778Y974371D03*
X1775863Y978735D03*
X1775963Y985825D03*
X1792236Y942480D03*
X1806452Y942675D03*
X1787163Y1009741D03*
X1769863Y1018725D03*
X1778963Y999125D03*
X1774000Y991825D03*
X1813850Y1083673D03*
X1810250Y1074723D03*
X1799350Y1095173D03*
X1807350Y1152673D03*
X1807527Y1185306D03*
X1841021Y156822D03*
X1845667Y176775D03*
X1833350Y194661D03*
X1851919Y199644D03*
X1859117Y193744D03*
X1821350Y194661D03*
X1842167Y172575D03*
X1850517Y165225D03*
X1823904Y165911D03*
X1831323Y274905D03*
X1860669Y262161D03*
X1859841Y452000D03*
X1844832Y446400D03*
X1853392Y476500D03*
X1840000Y513000D03*
X1854800Y513100D03*
X1845667Y629531D03*
X1833350Y647417D03*
X1859117Y646500D03*
X1821350Y647417D03*
X1842167Y625331D03*
X1850417Y617981D03*
X1823543Y618667D03*
X1840891Y610086D03*
X1851667Y652500D03*
X1847500Y659100D03*
X1821900Y676400D03*
X1830850Y730417D03*
X1854028Y713674D03*
X1814600Y983125D03*
X1857100Y1086300D03*
X1833350Y1100173D03*
X1851981Y1103613D03*
X1859974Y1109049D03*
X1821350Y1100173D03*
X1844432Y1099891D03*
X1831089Y1181419D03*
X1844138Y1240750D03*
X1845845Y1234445D03*
X1860457Y1229857D03*
X1856642Y1233142D03*
X1874400Y190744D03*
X1864775Y182057D03*
X1871200Y234100D03*
Y262000D03*
X1863781Y429200D03*
X1874500Y643500D03*
X1864000Y638000D03*
X1871000Y686600D03*
X1870198Y713498D03*
X1867652Y865421D03*
X1876555Y1070799D03*
X1872967Y1067014D03*
X1877045Y1138812D03*
X1871802Y1182620D03*
G54D23*
X67937Y205261D03*
X60037Y179561D03*
Y632317D03*
X67937Y657917D03*
X30993Y692869D03*
X30626Y667518D03*
X67937Y1110673D03*
X59937Y1085073D03*
X30206Y1120485D03*
X30573Y1145836D03*
X92237Y191161D03*
X88596Y629631D03*
X92237Y643917D03*
X120395Y999067D03*
X92237Y1096673D03*
X153703Y714355D03*
X154312Y1158233D03*
X153882Y1186220D03*
X184149Y179661D03*
X192149Y204961D03*
X216449Y191161D03*
X187095Y587067D03*
X216449Y633417D03*
X188599Y621417D03*
X204502Y620496D03*
X191849Y1106373D03*
X216449Y1096673D03*
X184427Y1094839D03*
X184439Y1099043D03*
X308362Y179661D03*
X308462Y632417D03*
X277970Y714099D03*
X308362Y1085173D03*
X278526Y1158233D03*
X278096Y1186220D03*
X319155Y68379D03*
X329479Y68345D03*
X316362Y205061D03*
X340662Y191161D03*
X337132Y629429D03*
X340662Y644017D03*
X316362Y657717D03*
Y1110573D03*
X340762Y1096773D03*
X402127Y714027D03*
X402353Y1185011D03*
X432674Y179661D03*
X440574Y205061D03*
X432674Y632317D03*
X440674Y657817D03*
X453373Y1104326D03*
X464874Y191161D03*
X461303Y629682D03*
X464874Y643917D03*
X508174Y1110573D03*
X556787Y179561D03*
X526223Y714280D03*
X526451Y1163084D03*
X526317Y1186666D03*
X589087Y191161D03*
X564887Y204861D03*
X592479Y566331D03*
X589087Y643917D03*
X556887Y632317D03*
X564887Y657717D03*
X564787Y1110473D03*
X589087Y1096673D03*
X556887Y1085173D03*
X616958Y538745D03*
Y542745D03*
X650657Y714197D03*
X651166Y1160810D03*
X650576Y1186007D03*
X694257Y107247D03*
X689000Y205161D03*
X681000Y179561D03*
X685450Y631917D03*
X701353Y630996D03*
X689000Y657917D03*
X688700Y1106273D03*
X680600Y1093100D03*
X713300Y191161D03*
Y643917D03*
Y1096673D03*
X885200Y41500D03*
X878257Y378495D03*
X882973Y816103D03*
X874523Y814580D03*
X881073Y856903D03*
X936981Y912047D03*
X936713Y1028083D03*
X936624Y1032390D03*
X961700Y1552700D03*
X1022568Y-40100D03*
X1014100Y58900D03*
Y63600D03*
Y54200D03*
X1014872Y545207D03*
X1014806Y554532D03*
X1034214Y872741D03*
X1032929Y1324216D03*
X1038053Y1349992D03*
X1032929Y1337616D03*
X1033029Y1342668D03*
X1032929Y1330916D03*
X1065571Y-80978D03*
X1042258Y-75936D03*
X1069618Y22405D03*
X1044173Y835703D03*
X1042073Y872703D03*
X1104300Y-78400D03*
X1113321Y-80838D03*
X1104379Y-86862D03*
X1089268Y-87500D03*
X1089250Y-60300D03*
X1180402Y96794D03*
X1180249Y101360D03*
X1183000Y249800D03*
X1190832D03*
X1229647Y1145325D03*
X1256700Y244861D03*
X1243764Y1145413D03*
X1314021Y90855D03*
Y86155D03*
X1345703Y133842D03*
X1332700Y194661D03*
X1363928Y542311D03*
X1332700Y647417D03*
Y1100173D03*
X1365354Y1123365D03*
X1364663Y1147073D03*
X1417769Y520457D03*
Y527857D03*
X1425400Y549600D03*
Y553600D03*
X1378913Y697517D03*
Y1150273D03*
X1456913Y194661D03*
X1451900Y526100D03*
X1459900D03*
X1432400Y540100D03*
X1456913Y647417D03*
Y1100173D03*
X1503225Y244661D03*
X1486800Y525900D03*
X1483800Y530900D03*
X1485800Y560400D03*
Y556100D03*
X1503125Y697517D03*
X1489058Y1117943D03*
X1503125Y1150373D03*
X1489283Y1144062D03*
X1581125Y194661D03*
X1576125Y649417D03*
X1590225Y1093873D03*
X1628938Y244661D03*
X1627338Y697517D03*
X1627513Y1128071D03*
X1627748Y1106754D03*
X1639138Y1150273D03*
X1705338Y194661D03*
Y647417D03*
Y1100173D03*
X1753750Y244661D03*
X1762195Y1011067D03*
X1736695Y1120127D03*
X1751550Y1150273D03*
X1736891Y1145478D03*
X1829550Y194661D03*
X1859669Y204961D03*
X1851717Y194075D03*
X1829550Y647417D03*
X1851717Y646831D03*
X1859669Y657817D03*
X1829550Y1100173D03*
X1859791Y1098787D03*
X1851696Y1098813D03*
G54D14*
X31496Y882677D03*
X168307Y646457D03*
X660236D03*
X718110Y820866D03*
X1366142Y646457D03*
X1462992Y866929D03*
X1602756Y646457D03*
X1903346Y803937D03*
G54D50*
X94237Y284461D03*
Y276861D03*
Y737217D03*
Y729617D03*
Y1189973D03*
Y1182373D03*
X218449Y284461D03*
Y276861D03*
Y737217D03*
Y729617D03*
Y1189973D03*
Y1182373D03*
X342662Y284461D03*
Y276861D03*
Y737217D03*
Y729617D03*
Y1189973D03*
Y1182373D03*
X466874Y284461D03*
Y276861D03*
Y737217D03*
Y729617D03*
Y1189973D03*
Y1182373D03*
X591087Y284461D03*
Y276861D03*
X587974Y513895D03*
Y521495D03*
X563279Y519131D03*
Y511531D03*
X591087Y737217D03*
Y729617D03*
Y1189973D03*
Y1182373D03*
X715300Y284461D03*
Y276861D03*
Y737217D03*
Y729617D03*
Y1189973D03*
Y1182373D03*
X880200Y693200D03*
Y700800D03*
X932500Y1505500D03*
Y1497900D03*
X964035Y1496252D03*
Y1503852D03*
X956286Y1502925D03*
Y1510525D03*
X1018483Y1460325D03*
Y1467925D03*
X1074455Y1459711D03*
Y1467311D03*
X1046355Y1459711D03*
Y1467311D03*
X1313000Y287361D03*
Y294961D03*
X1305000Y287361D03*
Y294961D03*
X1313000Y740117D03*
X1305000D03*
X1313000Y747717D03*
X1305000D03*
X1313000Y1192873D03*
Y1200473D03*
X1305000Y1192873D03*
Y1200473D03*
X1402257Y549931D03*
Y542331D03*
X1437213Y287361D03*
Y294961D03*
X1429213Y287361D03*
Y294961D03*
X1441631Y581215D03*
Y573615D03*
X1464700Y573300D03*
Y580900D03*
X1437213Y740117D03*
X1429213D03*
X1437213Y747717D03*
X1429213D03*
X1437213Y1192873D03*
Y1200473D03*
X1429213Y1192873D03*
Y1200473D03*
X1561425Y287361D03*
Y294961D03*
X1553425Y287361D03*
Y294961D03*
X1561425Y740117D03*
X1553425D03*
X1561425Y747717D03*
X1553425D03*
Y1192873D03*
Y1200473D03*
X1561425Y1192873D03*
Y1200473D03*
X1685638Y287361D03*
Y294961D03*
X1677638Y287361D03*
Y294961D03*
X1685638Y740117D03*
X1677638D03*
X1685638Y747717D03*
X1677638D03*
X1685638Y1192873D03*
Y1200473D03*
X1677638Y1192873D03*
Y1200473D03*
X1809850Y287361D03*
Y294961D03*
X1801850Y287361D03*
Y294961D03*
X1809968Y740294D03*
X1801968D03*
X1809968Y747894D03*
X1801968D03*
X1809850Y1192873D03*
Y1200473D03*
X1801850Y1192873D03*
Y1200473D03*
X1885969Y284461D03*
Y276861D03*
Y737217D03*
Y729617D03*
X1865992Y1146330D03*
Y1138730D03*
X1885969Y1189973D03*
Y1182373D03*
G54D32*
X50937Y245661D03*
X55937D03*
X60937D03*
X65937D03*
Y225661D03*
X60937D03*
X55937D03*
X50937D03*
Y698417D03*
X55937D03*
X60937D03*
X65937D03*
Y678417D03*
X60937D03*
X55937D03*
X50937D03*
X65937Y1131173D03*
X60937D03*
X55937D03*
X50937D03*
Y1151173D03*
X55937D03*
X60937D03*
X65937D03*
X88937Y207661D03*
X83937D03*
X78937D03*
X73937D03*
Y227661D03*
X78937D03*
X83937D03*
X88937D03*
Y660417D03*
X83937D03*
X78937D03*
X73937D03*
Y680417D03*
X78937D03*
X83937D03*
X88937D03*
Y1113173D03*
X83937D03*
X78937D03*
X73937D03*
Y1133173D03*
X78937D03*
X83937D03*
X88937D03*
X213149Y207661D03*
X208149D03*
X203149D03*
X198149D03*
X175149Y245661D03*
X180149D03*
X185149D03*
X190149D03*
Y225661D03*
X185149D03*
X180149D03*
X175149D03*
X198149Y227661D03*
X203149D03*
X208149D03*
X213149D03*
X175149Y698417D03*
X180149D03*
X185149D03*
X190149D03*
Y678417D03*
X185149D03*
X180149D03*
X175149D03*
X213149Y660417D03*
X208149D03*
X203149D03*
X198149D03*
Y680417D03*
X203149D03*
X208149D03*
X213149D03*
X190149Y1131173D03*
X185149D03*
X180149D03*
X175149D03*
X213149Y1113173D03*
X208149D03*
X203149D03*
X198149D03*
Y1133173D03*
X203149D03*
X208149D03*
X213149D03*
X175149Y1151173D03*
X180149D03*
X185149D03*
X190149D03*
X299362Y245661D03*
X304362D03*
X309362D03*
X314362D03*
Y225661D03*
X309362D03*
X304362D03*
X299362D03*
Y698417D03*
X304362D03*
X309362D03*
X314362D03*
Y678417D03*
X309362D03*
X304362D03*
X299362D03*
X314362Y1131173D03*
X309362D03*
X304362D03*
X299362D03*
Y1151173D03*
X304362D03*
X309362D03*
X314362D03*
X337362Y207661D03*
X332362D03*
X327362D03*
X322362D03*
Y227661D03*
X327362D03*
X332362D03*
X337362D03*
Y660417D03*
X332362D03*
X327362D03*
X322362D03*
Y680417D03*
X327362D03*
X332362D03*
X337362D03*
Y1113173D03*
X332362D03*
X327362D03*
X322362D03*
Y1133173D03*
X327362D03*
X332362D03*
X337362D03*
X456574Y207661D03*
X451574D03*
X446574D03*
Y227661D03*
X451574D03*
X456574D03*
X423574Y245661D03*
X428574D03*
X433574D03*
X438574D03*
Y225661D03*
X433574D03*
X428574D03*
X423574D03*
Y698417D03*
X428574D03*
X433574D03*
X438574D03*
Y678417D03*
X433574D03*
X428574D03*
X423574D03*
X456574Y660417D03*
X451574D03*
X446574D03*
Y680417D03*
X451574D03*
X456574D03*
X457100Y1130200D03*
X452100D03*
X447100D03*
Y1150200D03*
X452100D03*
X457100D03*
X461574Y207661D03*
Y227661D03*
Y660417D03*
Y680417D03*
X462100Y1130200D03*
Y1150200D03*
X547787Y245661D03*
X552787D03*
Y225661D03*
X547787D03*
Y698417D03*
X552787D03*
Y678417D03*
X547787D03*
X552787Y1131173D03*
X547787D03*
X529474Y1113073D03*
X524474D03*
X519474D03*
X514474D03*
Y1133073D03*
X519474D03*
X524474D03*
X529474D03*
X547787Y1151173D03*
X552787D03*
X585787Y207661D03*
X580787D03*
X575787D03*
X570787D03*
Y227661D03*
X575787D03*
X580787D03*
X585787D03*
X557787Y245661D03*
X562787D03*
Y225661D03*
X557787D03*
Y698417D03*
X562787D03*
Y678417D03*
X557787D03*
X585787Y660417D03*
X580787D03*
X575787D03*
X570787D03*
Y680417D03*
X575787D03*
X580787D03*
X585787D03*
X562787Y1131173D03*
X557787D03*
X585787Y1113173D03*
X580787D03*
X575787D03*
X570787D03*
Y1133173D03*
X575787D03*
X580787D03*
X585787D03*
X557787Y1151173D03*
X562787D03*
X700000Y207661D03*
X695000D03*
Y227661D03*
X700000D03*
X672000Y245661D03*
X677000D03*
X682000D03*
X687000D03*
Y225661D03*
X682000D03*
X677000D03*
X672000D03*
Y698417D03*
X677000D03*
X682000D03*
X687000D03*
Y678417D03*
X682000D03*
X677000D03*
X672000D03*
X700000Y660417D03*
X695000D03*
Y680417D03*
X700000D03*
X687000Y1131173D03*
X682000D03*
X677000D03*
X672000D03*
X700000Y1113173D03*
X695000D03*
Y1133173D03*
X700000D03*
X672000Y1151173D03*
X677000D03*
X682000D03*
X687000D03*
X710000Y207661D03*
X705000D03*
Y227661D03*
X710000D03*
Y660417D03*
X705000D03*
Y680417D03*
X710000D03*
Y1113173D03*
X705000D03*
Y1133173D03*
X710000D03*
X999500Y1174500D03*
X1004500D03*
X1009500D03*
X1014500D03*
Y1154500D03*
X1009500D03*
X1004500D03*
X999500D03*
X1318500Y254161D03*
X1323500D03*
X1328500D03*
Y234161D03*
X1323500D03*
X1318500D03*
X1328500Y686917D03*
X1323500D03*
X1318500D03*
Y706917D03*
X1323500D03*
X1328500D03*
X1318500Y1159673D03*
X1323500D03*
X1328500D03*
Y1139673D03*
X1323500D03*
X1318500D03*
X1333500Y254161D03*
Y234161D03*
Y686917D03*
Y706917D03*
Y1159673D03*
Y1139673D03*
X1442713Y254161D03*
X1447713D03*
X1452713D03*
X1457713D03*
Y234161D03*
X1452713D03*
X1447713D03*
X1442713D03*
X1457713Y686917D03*
X1452713D03*
X1447713D03*
X1442713D03*
Y706917D03*
X1447713D03*
X1452713D03*
X1457713D03*
X1442713Y1159673D03*
X1447713D03*
X1452713D03*
X1457713D03*
Y1139673D03*
X1452713D03*
X1447713D03*
X1442713D03*
X1566925Y254161D03*
X1571925D03*
Y234161D03*
X1566925D03*
X1571925Y686917D03*
X1566925D03*
Y706917D03*
X1571925D03*
X1564073Y1105175D03*
X1559073D03*
X1554073D03*
X1549073D03*
Y1125175D03*
X1554073D03*
X1559073D03*
X1564073D03*
X1576925Y254161D03*
X1581925D03*
Y234161D03*
X1576925D03*
X1581925Y686917D03*
X1576925D03*
Y706917D03*
X1581925D03*
X1691138Y254161D03*
X1696138D03*
X1701138D03*
X1706138D03*
Y234161D03*
X1701138D03*
X1696138D03*
X1691138D03*
X1706138Y686917D03*
X1701138D03*
X1696138D03*
X1691138D03*
Y706917D03*
X1696138D03*
X1701138D03*
X1706138D03*
X1691138Y1159673D03*
X1696138D03*
X1701138D03*
X1706138D03*
Y1139673D03*
X1701138D03*
X1696138D03*
X1691138D03*
X1842669Y245661D03*
X1847669D03*
X1852669D03*
X1857669D03*
Y225661D03*
X1852669D03*
X1847669D03*
X1842669D03*
X1815350Y254161D03*
X1820350D03*
X1825350D03*
X1830350D03*
Y234161D03*
X1825350D03*
X1820350D03*
X1815350D03*
X1842669Y698417D03*
X1847669D03*
X1852669D03*
X1857669D03*
Y678417D03*
X1852669D03*
X1847669D03*
X1842669D03*
X1830350Y686917D03*
X1825350D03*
X1820350D03*
X1815350D03*
Y706917D03*
X1820350D03*
X1825350D03*
X1830350D03*
X1858277Y1125264D03*
X1853277D03*
X1848277D03*
X1843277D03*
Y1145264D03*
X1848277D03*
X1853277D03*
X1858277D03*
X1815350Y1159673D03*
X1820350D03*
X1825350D03*
X1830350D03*
Y1139673D03*
X1825350D03*
X1820350D03*
X1815350D03*
X1880669Y207661D03*
X1875669D03*
X1870669D03*
X1865669D03*
Y227661D03*
X1870669D03*
X1875669D03*
X1880669D03*
Y660417D03*
X1875669D03*
X1870669D03*
X1865669D03*
Y680417D03*
X1870669D03*
X1875669D03*
X1880669D03*
X1880779Y1097763D03*
X1875779D03*
X1870779D03*
X1865779D03*
Y1117763D03*
X1870779D03*
X1875779D03*
X1880779D03*
G54D41*
X111024Y141870D03*
Y314114D03*
Y594626D03*
Y766870D03*
Y1047382D03*
Y1219626D03*
X235236Y141870D03*
Y314114D03*
Y594626D03*
Y766870D03*
Y1047382D03*
Y1219626D03*
X359449Y141870D03*
Y314114D03*
Y594626D03*
Y766870D03*
Y1047382D03*
Y1219626D03*
X483661Y141870D03*
Y314114D03*
Y594626D03*
Y766870D03*
Y1047382D03*
Y1219626D03*
X607874Y141870D03*
Y314114D03*
Y594626D03*
Y766870D03*
Y1047382D03*
Y1219626D03*
X732087Y141870D03*
Y314114D03*
Y594626D03*
Y766870D03*
Y1047382D03*
Y1219626D03*
X938091Y-115157D03*
X1110335D03*
X1281693Y141870D03*
Y314114D03*
Y594626D03*
Y766870D03*
Y1047382D03*
Y1219626D03*
X1405906Y141870D03*
Y314114D03*
Y594626D03*
Y766870D03*
Y1047382D03*
Y1219626D03*
X1530118Y141870D03*
Y314114D03*
Y594626D03*
Y766870D03*
Y1047382D03*
Y1219626D03*
X1654331Y141870D03*
Y314114D03*
Y594626D03*
Y766870D03*
Y1047382D03*
Y1219626D03*
X1778543Y141870D03*
Y314114D03*
Y594626D03*
Y766870D03*
Y1047382D03*
Y1219626D03*
X1902756Y141870D03*
Y314114D03*
Y594626D03*
Y766870D03*
Y1047382D03*
Y1219626D03*
G54D107*
X1265178Y171892D03*
X1267378D03*
X1265178Y174092D03*
X1267378D03*
Y624648D03*
X1265178D03*
X1267378Y626848D03*
X1265178D03*
X1267378Y1077404D03*
X1265178D03*
X1267378Y1079604D03*
X1265178D03*
X1391591Y171892D03*
X1389391D03*
X1391591Y174092D03*
X1389391D03*
X1391591Y624648D03*
X1389391D03*
X1391591Y626848D03*
X1389391D03*
X1391591Y1077404D03*
X1389391D03*
X1391591Y1079604D03*
X1389391D03*
X1515803Y171892D03*
X1513603D03*
X1515803Y174092D03*
X1513603D03*
X1515803Y624648D03*
X1513603D03*
X1515803Y626848D03*
X1513603D03*
X1515803Y1077404D03*
X1513603D03*
X1515803Y1079604D03*
X1513603D03*
X1640016Y171892D03*
X1637816D03*
X1640016Y174092D03*
X1637816D03*
X1640016Y624648D03*
X1637816D03*
X1640016Y626848D03*
X1637816D03*
X1640016Y1077404D03*
X1637816D03*
X1640016Y1079604D03*
X1637816D03*
X1764228Y171892D03*
X1762028D03*
X1764228Y174092D03*
X1762028D03*
X1739228Y624648D03*
X1737028D03*
X1739228Y626848D03*
X1737028D03*
X1764228Y1077404D03*
X1762028D03*
X1764228Y1079604D03*
X1762028D03*
X1888441Y171892D03*
X1886241D03*
X1888441Y174092D03*
X1886241D03*
X1888441Y624648D03*
X1886241D03*
X1888441Y626848D03*
X1886241D03*
X1888441Y1077404D03*
X1886241D03*
X1888441Y1079604D03*
X1886241D03*
G54D24*
X64537Y205261D03*
X56637Y179561D03*
Y632317D03*
X64537Y657917D03*
X27593Y692869D03*
X27226Y667518D03*
X64537Y1110673D03*
X56537Y1085073D03*
X26806Y1120485D03*
X27173Y1145836D03*
X88837Y191161D03*
X85196Y629631D03*
X88837Y643917D03*
X116995Y999067D03*
X88837Y1096673D03*
X150303Y714355D03*
X150912Y1158233D03*
X150482Y1186220D03*
X180749Y179661D03*
X188749Y204961D03*
X213049Y191161D03*
X183695Y587067D03*
X213049Y633417D03*
X185199Y621417D03*
X201102Y620496D03*
X188449Y1106373D03*
X213049Y1096673D03*
X181027Y1094839D03*
X181039Y1099043D03*
X304962Y179661D03*
X312962Y205061D03*
X305062Y632417D03*
X312962Y657717D03*
X274570Y714099D03*
X312962Y1110573D03*
X304962Y1085173D03*
X275126Y1158233D03*
X274696Y1186220D03*
X315755Y68379D03*
X326079Y68345D03*
X337262Y191161D03*
X333732Y629429D03*
X337262Y644017D03*
X337362Y1096773D03*
X398727Y714027D03*
X398953Y1185011D03*
X429274Y179661D03*
X437174Y205061D03*
X457903Y629682D03*
X429274Y632317D03*
X437274Y657817D03*
X449973Y1104326D03*
X461474Y191161D03*
Y643917D03*
X504774Y1110573D03*
X553387Y179561D03*
X553487Y632317D03*
X522823Y714280D03*
X553487Y1085173D03*
X523051Y1163084D03*
X522917Y1186666D03*
X585687Y191161D03*
X561487Y204861D03*
X589079Y566331D03*
X585687Y643917D03*
X561487Y657717D03*
X561387Y1110473D03*
X585687Y1096673D03*
X613558Y538745D03*
Y542745D03*
X647257Y714197D03*
X647766Y1160810D03*
X647176Y1186007D03*
X690857Y107247D03*
X685600Y205161D03*
X677600Y179561D03*
X682050Y631917D03*
X697953Y630996D03*
X685600Y657917D03*
X685300Y1106273D03*
X677200Y1093100D03*
X709900Y191161D03*
Y643917D03*
Y1096673D03*
X881800Y41500D03*
X874857Y378495D03*
X879573Y816103D03*
X871123Y814580D03*
X877673Y856903D03*
X933581Y912047D03*
X933313Y1028083D03*
X933224Y1032390D03*
X958300Y1552700D03*
X1019168Y-40100D03*
X1038858Y-75936D03*
X1010700Y58900D03*
Y63600D03*
Y54200D03*
X1011472Y545207D03*
X1011406Y554532D03*
X1030814Y872741D03*
X1038673Y872703D03*
X1029529Y1324216D03*
X1034653Y1349992D03*
X1029529Y1337616D03*
X1029629Y1342668D03*
X1029529Y1330916D03*
X1085868Y-87500D03*
X1062171Y-80978D03*
X1085850Y-60300D03*
X1066218Y22405D03*
X1040773Y835703D03*
X1100900Y-78400D03*
X1109921Y-80838D03*
X1100979Y-86862D03*
X1177002Y96794D03*
X1176849Y101360D03*
X1179600Y249800D03*
X1187432D03*
X1226247Y1145325D03*
X1253300Y244861D03*
X1240364Y1145413D03*
X1310621Y90855D03*
Y86155D03*
X1329300Y194661D03*
Y647417D03*
Y1100173D03*
X1342303Y133842D03*
X1360528Y542311D03*
X1375513Y697517D03*
X1361954Y1123365D03*
X1375513Y1150273D03*
X1361263Y1147073D03*
X1414369Y520457D03*
Y527857D03*
X1422000Y549600D03*
Y553600D03*
X1453513Y194661D03*
X1448500Y526100D03*
X1456500D03*
X1429000Y540100D03*
X1453513Y647417D03*
Y1100173D03*
X1499825Y244661D03*
X1483400Y525900D03*
X1480400Y530900D03*
X1482400Y560400D03*
Y556100D03*
X1499725Y697517D03*
X1485658Y1117943D03*
X1499725Y1150373D03*
X1485883Y1144062D03*
X1577725Y194661D03*
X1572725Y649417D03*
X1586825Y1093873D03*
X1625538Y244661D03*
X1623938Y697517D03*
X1624113Y1128071D03*
X1624348Y1106754D03*
X1635738Y1150273D03*
X1701938Y194661D03*
Y647417D03*
Y1100173D03*
X1750350Y244661D03*
X1758795Y1011067D03*
X1733295Y1120127D03*
X1748150Y1150273D03*
X1733491Y1145478D03*
X1826150Y194661D03*
X1856269Y204961D03*
X1848317Y194075D03*
X1826150Y647417D03*
X1848317Y646831D03*
X1856269Y657817D03*
X1826150Y1100173D03*
X1856391Y1098787D03*
X1848296Y1098813D03*
G54D15*
X25000Y1200800D03*
X30000D03*
X95437Y295961D03*
Y748717D03*
Y1201473D03*
X135422Y1201337D03*
X140422D03*
X219649Y295961D03*
Y748717D03*
X259594Y1201168D03*
X264594D03*
X219649Y1201473D03*
X343862Y295961D03*
Y748717D03*
Y1201473D03*
X383849Y1201042D03*
X388849D03*
X468074Y295961D03*
Y748717D03*
X508103Y1200957D03*
X468074Y1201473D03*
X513103Y1200957D03*
X592287Y295961D03*
X584279Y572631D03*
X592287Y748717D03*
Y1201473D03*
X607460Y566574D03*
X632316Y1200874D03*
X637316D03*
X716500Y295961D03*
Y748717D03*
Y1201473D03*
X751209Y165428D03*
X752500Y1163300D03*
X881256Y1370750D03*
X933524Y927700D03*
X967813Y1559566D03*
X953500Y1559000D03*
X1211205Y1161994D03*
X1216205D03*
X1298500Y295461D03*
Y265961D03*
Y718717D03*
Y748217D03*
Y1171473D03*
Y1200973D03*
X1351321Y1161953D03*
X1346321D03*
X1422713Y295461D03*
Y265961D03*
X1426419Y532557D03*
X1422713Y718717D03*
Y748217D03*
Y1171473D03*
Y1200973D03*
X1470953Y1161827D03*
X1475953D03*
X1507037Y533703D03*
X1546925Y295461D03*
Y265961D03*
Y718717D03*
Y748217D03*
Y1171473D03*
Y1200973D03*
X1615552Y1162006D03*
X1620236D03*
X1671138Y295461D03*
Y265961D03*
Y718717D03*
Y748217D03*
Y1171473D03*
Y1200973D03*
X1760500Y730800D03*
X1723117Y1161953D03*
X1718117D03*
X1795350Y295461D03*
Y265961D03*
Y718717D03*
X1795468Y748394D03*
X1795350Y1171473D03*
Y1200973D03*
X1836400Y1161500D03*
X1841084Y1161521D03*
X1887169Y295961D03*
Y748717D03*
Y1201473D03*
G54D51*
X131201Y377154D03*
X131200Y829910D03*
X131201Y1282666D03*
X379232Y377154D03*
Y829910D03*
Y1282666D03*
X627263Y377154D03*
Y829910D03*
Y1282666D03*
X796457Y263003D03*
Y735444D03*
X961418Y1087413D03*
Y1429932D03*
X1181890Y555917D03*
X1181870Y969280D03*
X1181890Y1559854D03*
X1301870Y377154D03*
Y829910D03*
Y1282666D03*
X1549901Y377154D03*
Y829910D03*
Y1282666D03*
X1797933Y377154D03*
Y829910D03*
Y1282666D03*
G54D108*
X1328500Y210661D03*
Y205661D03*
Y200661D03*
X1308500D03*
Y205661D03*
Y210661D03*
X1328500Y215661D03*
X1308500D03*
X1328500Y668417D03*
Y663417D03*
Y658417D03*
Y653417D03*
X1308500D03*
Y658417D03*
Y663417D03*
Y668417D03*
X1328500Y1121173D03*
Y1116173D03*
Y1111173D03*
Y1106173D03*
X1308500D03*
Y1111173D03*
Y1116173D03*
Y1121173D03*
X1452713Y210661D03*
Y205661D03*
Y200661D03*
X1432713D03*
Y205661D03*
Y210661D03*
X1452713Y215661D03*
X1432713D03*
X1452713Y668417D03*
Y663417D03*
Y658417D03*
Y653417D03*
X1432713D03*
Y658417D03*
Y663417D03*
Y668417D03*
X1452713Y1121173D03*
Y1116173D03*
Y1111173D03*
Y1106173D03*
X1432713D03*
Y1111173D03*
Y1116173D03*
Y1121173D03*
X1556925Y200661D03*
Y205661D03*
Y210661D03*
Y215661D03*
X1571925Y670417D03*
Y665417D03*
Y660417D03*
Y655417D03*
X1551925D03*
Y660417D03*
Y665417D03*
Y670417D03*
X1572100Y1099700D03*
Y1104700D03*
Y1109700D03*
Y1114700D03*
X1576925Y210661D03*
Y205661D03*
Y200661D03*
Y215661D03*
X1592100Y1114700D03*
Y1109700D03*
Y1104700D03*
Y1099700D03*
X1701138Y210661D03*
Y205661D03*
Y200661D03*
X1681138D03*
Y205661D03*
Y210661D03*
X1701138Y215661D03*
X1681138D03*
X1701138Y668417D03*
Y663417D03*
Y658417D03*
Y653417D03*
X1681138D03*
Y658417D03*
Y663417D03*
Y668417D03*
X1701138Y1121173D03*
Y1116173D03*
Y1111173D03*
Y1106173D03*
X1681138D03*
Y1111173D03*
Y1116173D03*
Y1121173D03*
X1805350Y200661D03*
Y205661D03*
Y210661D03*
Y215661D03*
Y653417D03*
Y658417D03*
Y663417D03*
Y668417D03*
X1803350Y1106173D03*
Y1111173D03*
Y1116173D03*
Y1121173D03*
X1825350Y210661D03*
Y205661D03*
Y200661D03*
Y215661D03*
Y668417D03*
Y663417D03*
Y658417D03*
Y653417D03*
X1823350Y1121173D03*
Y1116173D03*
Y1111173D03*
Y1106173D03*
G54D60*
X317812Y103731D03*
X591779Y539031D03*
X568779Y516531D03*
X621058Y538945D03*
X696787Y584595D03*
X752500Y1140200D03*
X870163Y840253D03*
X943500Y1008900D03*
X928384Y1349782D03*
X928439Y1363514D03*
X942925Y1372857D03*
X938000Y1502900D03*
X948845Y934950D03*
X961000Y1525400D03*
X1031563Y856553D03*
X992994Y1009540D03*
X1021200Y1100800D03*
X1068700Y1101800D03*
X1111600Y1101600D03*
X1317655Y112751D03*
X1376243Y574719D03*
X1460200Y518300D03*
X1452200D03*
X1439200D03*
X1465700D03*
X1433200Y562800D03*
X1487541Y535562D03*
X1883000Y187444D03*
Y640200D03*
G54D33*
X60237Y214661D03*
Y667417D03*
Y1120173D03*
X142737Y240661D03*
Y693417D03*
X142056Y971762D03*
X142737Y1146173D03*
X184449Y214661D03*
X208756Y559762D03*
X206300Y644000D03*
X190199Y671689D03*
X190249Y1123673D03*
X308662Y214661D03*
X266949Y240661D03*
X308662Y667417D03*
X266949Y693417D03*
X308662Y1120173D03*
X266949Y1146173D03*
X342529Y58745D03*
X391162Y240661D03*
Y693417D03*
Y1146173D03*
X432874Y214661D03*
Y667417D03*
X453474Y1117073D03*
X503374Y1141973D03*
X515374Y240661D03*
Y693417D03*
X557087Y214661D03*
X601901Y530600D03*
X557087Y667417D03*
Y1120173D03*
X639587Y240661D03*
Y693417D03*
Y1146173D03*
X694117Y112738D03*
X681300Y214661D03*
X681800Y669917D03*
X687100Y1124073D03*
X753000Y209600D03*
X751800Y681800D03*
X851404Y1538590D03*
X935378Y995820D03*
X914846Y1530405D03*
X971122Y1516969D03*
X1034512Y-70708D03*
X1057833Y-76247D03*
X1086507Y1561743D03*
X1110888Y-55662D03*
X1311800Y195261D03*
Y648017D03*
Y1100773D03*
X1335300Y227761D03*
Y680517D03*
Y1133273D03*
X1436013Y195261D03*
X1459513Y227761D03*
X1436013Y648017D03*
X1459513Y680517D03*
X1436013Y1100773D03*
X1459513Y1133273D03*
X1560225Y195261D03*
X1555225Y650017D03*
X1552625Y1136373D03*
X1583725Y227761D03*
Y680517D03*
X1684438Y195261D03*
X1707938Y227761D03*
X1684438Y648017D03*
X1707938Y680517D03*
X1684438Y1100773D03*
X1707938Y1133273D03*
X1763300Y716500D03*
X1808650Y195261D03*
Y648017D03*
X1783856Y983762D03*
X1808650Y1100773D03*
X1851969Y214661D03*
X1832150Y227761D03*
X1851969Y667417D03*
X1832150Y680517D03*
X1858506Y1117394D03*
X1831750Y1133173D03*
X1884885Y1064038D03*
G54D42*
X111024Y153681D03*
Y606437D03*
Y1059193D03*
X235236Y153681D03*
Y606437D03*
Y1059193D03*
X359449Y153681D03*
Y606437D03*
Y1059193D03*
X483661Y153681D03*
Y606437D03*
Y1059193D03*
X607874Y153681D03*
Y606437D03*
Y1059193D03*
X732087Y153681D03*
Y606437D03*
Y1059193D03*
X949902Y-115157D03*
X1281693Y153681D03*
Y606437D03*
Y1059193D03*
X1405906Y153681D03*
Y606437D03*
Y1059193D03*
X1530118Y153681D03*
Y606437D03*
Y1059193D03*
X1654331Y153681D03*
Y606437D03*
Y1059193D03*
X1778543Y153681D03*
Y606437D03*
Y1059193D03*
X1902756Y153681D03*
Y606437D03*
Y1059193D03*
G54D70*
X543338Y553169D03*
X567779Y570531D03*
X575779D03*
X588779D03*
X562279D03*
X876956Y1365750D03*
X929232Y921850D03*
X928194Y1373048D03*
X942879Y1361757D03*
X931500Y1556900D03*
X937000D03*
X973055Y1179453D03*
X945000Y1556900D03*
X958000D03*
X1032053Y-42075D03*
X999500Y1184200D03*
X1054625Y-47250D03*
X1320055Y71629D03*
X1436200Y549800D03*
X1459200Y572300D03*
X1598400Y1111200D03*
G54D43*
X99823Y211142D03*
Y207992D03*
Y204842D03*
Y201693D03*
Y198543D03*
Y217441D03*
Y214291D03*
Y670197D03*
Y667047D03*
Y663898D03*
Y660748D03*
Y657598D03*
Y654449D03*
Y651299D03*
Y1122953D03*
Y1119803D03*
Y1116654D03*
Y1113504D03*
Y1110354D03*
Y1107205D03*
Y1104055D03*
X224035Y211142D03*
Y207992D03*
Y204842D03*
Y201693D03*
Y198543D03*
Y217441D03*
Y214291D03*
Y670197D03*
Y667047D03*
Y663898D03*
Y660748D03*
Y657598D03*
Y654449D03*
Y651299D03*
Y1122953D03*
Y1119803D03*
Y1116654D03*
Y1113504D03*
Y1110354D03*
Y1107205D03*
Y1104055D03*
X348248Y211142D03*
Y207992D03*
Y204842D03*
Y201693D03*
Y198543D03*
Y217441D03*
Y214291D03*
Y670197D03*
Y667047D03*
Y663898D03*
Y660748D03*
Y657598D03*
Y654449D03*
Y651299D03*
Y1122953D03*
Y1119803D03*
Y1116654D03*
Y1113504D03*
Y1110354D03*
Y1107205D03*
Y1104055D03*
X472460Y211142D03*
Y207992D03*
Y204842D03*
Y201693D03*
Y198543D03*
Y217441D03*
Y214291D03*
Y670197D03*
Y667047D03*
Y663898D03*
Y660748D03*
Y657598D03*
Y654449D03*
Y651299D03*
Y1122953D03*
Y1119803D03*
Y1116654D03*
Y1113504D03*
Y1110354D03*
Y1107205D03*
Y1104055D03*
X596673Y211142D03*
Y207992D03*
Y204842D03*
Y201693D03*
Y198543D03*
Y217441D03*
Y214291D03*
Y670197D03*
Y667047D03*
Y663898D03*
Y660748D03*
Y657598D03*
Y654449D03*
Y651299D03*
Y1122953D03*
Y1119803D03*
Y1116654D03*
Y1113504D03*
Y1110354D03*
Y1107205D03*
Y1104055D03*
X720886Y211142D03*
Y207992D03*
Y204842D03*
Y201693D03*
Y198543D03*
Y217441D03*
Y214291D03*
Y670197D03*
Y667047D03*
Y663898D03*
Y660748D03*
Y657598D03*
Y654449D03*
Y651299D03*
Y1122953D03*
Y1119803D03*
Y1116654D03*
Y1113504D03*
Y1110354D03*
Y1107205D03*
Y1104055D03*
X1270492Y211142D03*
Y207992D03*
Y204842D03*
Y201693D03*
Y198543D03*
Y217441D03*
Y214291D03*
Y670197D03*
Y667047D03*
Y663898D03*
Y660748D03*
Y657598D03*
Y654449D03*
Y651299D03*
Y1122953D03*
Y1119803D03*
Y1116654D03*
Y1113504D03*
Y1110354D03*
Y1107205D03*
Y1104055D03*
X1394705Y211142D03*
Y207992D03*
Y204842D03*
Y201693D03*
Y198543D03*
Y217441D03*
Y214291D03*
Y670197D03*
Y667047D03*
Y663898D03*
Y660748D03*
Y657598D03*
Y654449D03*
Y651299D03*
Y1122953D03*
Y1119803D03*
Y1116654D03*
Y1113504D03*
Y1110354D03*
Y1107205D03*
Y1104055D03*
X1518917Y211142D03*
Y207992D03*
Y204842D03*
Y201693D03*
Y198543D03*
Y217441D03*
Y214291D03*
Y670197D03*
Y667047D03*
Y663898D03*
Y660748D03*
Y657598D03*
Y654449D03*
Y651299D03*
Y1122953D03*
Y1119803D03*
Y1116654D03*
Y1113504D03*
Y1110354D03*
Y1107205D03*
Y1104055D03*
X1643130Y211142D03*
Y207992D03*
Y204842D03*
Y201693D03*
Y198543D03*
Y217441D03*
Y214291D03*
Y670197D03*
Y667047D03*
Y663898D03*
Y660748D03*
Y657598D03*
Y654449D03*
Y651299D03*
Y1122953D03*
Y1119803D03*
Y1116654D03*
Y1113504D03*
Y1110354D03*
Y1107205D03*
Y1104055D03*
X1767342Y211142D03*
Y207992D03*
Y204842D03*
Y201693D03*
Y198543D03*
Y217441D03*
Y214291D03*
Y670197D03*
Y667047D03*
Y663898D03*
Y660748D03*
Y657598D03*
Y654449D03*
Y651299D03*
Y1122953D03*
Y1119803D03*
Y1116654D03*
Y1113504D03*
Y1110354D03*
Y1107205D03*
Y1104055D03*
X1891555Y211142D03*
Y207992D03*
Y204842D03*
Y201693D03*
Y198543D03*
Y217441D03*
Y214291D03*
Y670197D03*
Y667047D03*
Y663898D03*
Y660748D03*
Y657598D03*
Y654449D03*
Y651299D03*
Y1122953D03*
Y1119803D03*
Y1116654D03*
Y1113504D03*
Y1110354D03*
Y1107205D03*
Y1104055D03*
G54D109*
X1392452Y573397D03*
Y579803D03*
G54D61*
X317812Y107331D03*
X591779Y542631D03*
X568779Y520131D03*
X621058Y542545D03*
X696787Y588195D03*
X752500Y1143800D03*
X870163Y843853D03*
X943500Y1012500D03*
X928384Y1353382D03*
X928439Y1367114D03*
X942925Y1376457D03*
X938000Y1506500D03*
X948845Y938550D03*
X961000Y1529000D03*
X1031563Y860153D03*
X992994Y1013140D03*
X1021200Y1104400D03*
X1068700Y1105400D03*
X1111600Y1105200D03*
X1317655Y116351D03*
X1376243Y578319D03*
X1460200Y521900D03*
X1452200D03*
X1439200D03*
X1465700D03*
X1433200Y566400D03*
X1487541Y539162D03*
X1883000Y191044D03*
Y643800D03*
G54D34*
X56637Y214661D03*
Y667417D03*
Y1120173D03*
X139137Y240661D03*
Y693417D03*
X138456Y971762D03*
X139137Y1146173D03*
X180849Y214661D03*
X205156Y559762D03*
X202700Y644000D03*
X186599Y671689D03*
X186649Y1123673D03*
X263349Y240661D03*
Y693417D03*
Y1146173D03*
X305062Y214661D03*
Y667417D03*
Y1120173D03*
X338929Y58745D03*
X387562Y240661D03*
Y693417D03*
Y1146173D03*
X429274Y214661D03*
Y667417D03*
X449874Y1117073D03*
X499774Y1141973D03*
X511774Y240661D03*
X553487Y214661D03*
Y667417D03*
X511774Y693417D03*
X553487Y1120173D03*
X598301Y530600D03*
X635987Y240661D03*
Y693417D03*
Y1146173D03*
X690517Y112738D03*
X677700Y214661D03*
X678200Y669917D03*
X683500Y1124073D03*
X749400Y209600D03*
X748200Y681800D03*
X847804Y1538590D03*
X931778Y995820D03*
X911246Y1530405D03*
X967522Y1516969D03*
X1030912Y-70708D03*
X1054233Y-76247D03*
X1082907Y1561743D03*
X1107288Y-55662D03*
X1308200Y195261D03*
Y648017D03*
Y1100773D03*
X1331700Y227761D03*
Y680517D03*
Y1133273D03*
X1432413Y195261D03*
X1455913Y227761D03*
X1432413Y648017D03*
X1455913Y680517D03*
X1432413Y1100773D03*
X1455913Y1133273D03*
X1556625Y195261D03*
X1551625Y650017D03*
X1549025Y1136373D03*
X1580125Y227761D03*
Y680517D03*
X1680838Y195261D03*
X1704338Y227761D03*
X1680838Y648017D03*
X1704338Y680517D03*
X1680838Y1100773D03*
X1704338Y1133273D03*
X1759700Y716500D03*
X1805050Y195261D03*
Y648017D03*
X1780256Y983762D03*
X1805050Y1100773D03*
X1848369Y214661D03*
X1828550Y227761D03*
X1848369Y667417D03*
X1828550Y680517D03*
X1854906Y1117394D03*
X1828150Y1133173D03*
X1881285Y1064038D03*
G54D25*
X56737Y210561D03*
X58384Y513020D03*
X44157Y513016D03*
X56737Y663317D03*
Y1116073D03*
X88737Y176661D03*
Y181161D03*
Y633917D03*
X100863Y985725D03*
X116997Y995001D03*
X102163Y1003325D03*
X88837Y1082173D03*
Y1086673D03*
X139237Y244761D03*
X168411Y512874D03*
X168863Y591025D03*
X167563Y573725D03*
X139237Y697517D03*
X137163Y1005625D03*
X125363Y1001725D03*
X137122Y997250D03*
X124455Y992723D03*
X139237Y1150273D03*
X180949Y210561D03*
X213049Y181361D03*
Y176661D03*
X182638Y512878D03*
X203863Y593625D03*
X192063Y589725D03*
X203822Y585250D03*
X183697Y583001D03*
X191155Y580723D03*
X213049Y623417D03*
Y618917D03*
X202800Y650000D03*
X186699Y667589D03*
X213049Y1082173D03*
Y1086873D03*
X186749Y1119573D03*
X263449Y244761D03*
Y697517D03*
Y1150273D03*
X305162Y210561D03*
X306809Y512878D03*
X292582Y512874D03*
X305162Y663317D03*
Y1116073D03*
X315721Y72855D03*
X326079Y72845D03*
X337362Y176461D03*
X337262Y181161D03*
Y634017D03*
X337362Y1082073D03*
Y1086773D03*
X387662Y244761D03*
Y697517D03*
Y1150273D03*
X429374Y210561D03*
X430959Y512841D03*
X416732Y512837D03*
X429374Y663317D03*
X449974Y1112973D03*
X443973Y1091326D03*
X461474Y176461D03*
Y181161D03*
Y633917D03*
X499874Y1145973D03*
X553587Y210661D03*
X511874Y244661D03*
X541679Y528531D03*
Y532831D03*
X525277Y512878D03*
X511050Y512874D03*
X544179Y566531D03*
Y561531D03*
X553587Y663417D03*
X511874Y697417D03*
X553587Y1116173D03*
X585687Y176661D03*
Y181361D03*
X601579Y538831D03*
Y542831D03*
X576079Y566331D03*
X568079D03*
X595579Y552331D03*
X585687Y634017D03*
Y629417D03*
Y1082173D03*
Y1086873D03*
X621697Y107633D03*
X611701Y112329D03*
X636087Y244761D03*
X638684Y512541D03*
X624457Y512537D03*
X616110Y562574D03*
Y555174D03*
X636087Y697517D03*
Y1150273D03*
X677800Y210561D03*
X678300Y665817D03*
X683600Y1119973D03*
X709900Y176461D03*
Y181161D03*
X749500Y205500D03*
X709900Y633917D03*
Y629417D03*
X748300Y677700D03*
X709900Y1081973D03*
Y1086673D03*
X839000Y1538800D03*
X874850Y359100D03*
X874654Y445462D03*
X874700Y450200D03*
Y454900D03*
X874800Y471100D03*
X874754Y459562D03*
X874743Y464505D03*
X875943Y542405D03*
X885903Y856727D03*
X868672Y1358528D03*
X877912Y1380412D03*
X877911Y1375746D03*
X868508Y1523720D03*
X906900Y1512600D03*
Y1508100D03*
X937300Y1552700D03*
X916300Y1539200D03*
X913300Y1544200D03*
X968690Y1153500D03*
X945300Y1552700D03*
X976513Y1553466D03*
Y1549366D03*
X964832Y1538282D03*
X967800Y1529200D03*
Y1525200D03*
X1038858Y-71536D03*
X1015632Y-66200D03*
X1004132Y-43500D03*
X1011450Y550000D03*
X1025235Y908603D03*
X1025200Y904200D03*
X1009800Y930500D03*
X1034674Y1354526D03*
X1062121Y-76578D03*
X1062904Y79465D03*
X1046300Y442000D03*
X1046337Y429753D03*
X1046301Y434409D03*
X1046515Y557053D03*
X1109900Y-89600D03*
X1109921Y-85538D03*
X1100879Y-82462D03*
X1221510Y236291D03*
X1194650Y284750D03*
X1194429Y1033731D03*
Y1029031D03*
X1250061Y513463D03*
X1235924Y513432D03*
X1254800Y697850D03*
X1250525Y966004D03*
X1236376Y965973D03*
X1254800Y1150173D03*
X1308300Y191161D03*
Y643917D03*
Y1096673D03*
X1331800Y223661D03*
X1346413Y513334D03*
X1332276Y513303D03*
X1331800Y676417D03*
X1348846Y965705D03*
X1334805Y965825D03*
X1331800Y1129173D03*
X1381009Y244829D03*
X1432513Y191161D03*
X1456013Y223661D03*
X1435500Y526100D03*
X1432513Y643917D03*
X1456013Y676417D03*
X1473058Y965763D03*
X1459017Y965883D03*
X1456013Y1129173D03*
X1432513Y1096673D03*
X1556725Y191161D03*
X1551725Y645917D03*
X1549125Y1132273D03*
X1580225Y223661D03*
X1597295Y513418D03*
X1583158Y513387D03*
X1580225Y676417D03*
X1597371Y965889D03*
X1583230Y965809D03*
X1680938Y191161D03*
X1704438Y223661D03*
X1707623Y513134D03*
X1680938Y643917D03*
X1704438Y676417D03*
X1680938Y1096673D03*
X1704438Y1129173D03*
X1721760Y513165D03*
X1759800Y720500D03*
X1759934Y965756D03*
X1745736Y965664D03*
X1758797Y1007001D03*
X1743963Y1015325D03*
X1742663Y997725D03*
X1805150Y191161D03*
Y643917D03*
X1802627Y965626D03*
X1790438Y968689D03*
X1767163Y1013725D03*
X1778922Y1009250D03*
X1766255Y1004723D03*
X1778963Y1017625D03*
X1805150Y1096673D03*
X1848469Y210461D03*
X1842117Y181175D03*
X1828650Y223661D03*
X1845595Y513292D03*
X1831458Y513261D03*
X1842217Y633931D03*
X1828650Y676417D03*
X1848469Y663317D03*
X1828250Y1128973D03*
X1855006Y1113294D03*
X1881385Y1059938D03*
G54D52*
X128909Y171892D03*
X126709D03*
X128909Y174092D03*
X126709D03*
Y624648D03*
X128909D03*
X126709Y626848D03*
X128909D03*
X126709Y1077404D03*
X128909D03*
X126709Y1079604D03*
X128909D03*
X253121Y171892D03*
X250921D03*
X253121Y174092D03*
X250921D03*
Y626848D03*
X253121D03*
X250921Y624648D03*
X253121D03*
X250921Y1077404D03*
X253121D03*
X250921Y1079604D03*
X253121D03*
X377334Y171892D03*
X375134D03*
X377334Y174092D03*
X375134D03*
Y624648D03*
X377334D03*
X375134Y626848D03*
X377334D03*
X375134Y1077404D03*
X377334D03*
X375134Y1079604D03*
X377334D03*
X501546Y174092D03*
X499346D03*
X501546Y171892D03*
X499346D03*
Y624648D03*
X501546D03*
X499346Y626848D03*
X501546D03*
X499346Y1079604D03*
X501546D03*
X499346Y1077404D03*
X501546D03*
X625759Y174092D03*
X623559D03*
X625759Y171892D03*
X623559D03*
Y624648D03*
X625759D03*
X623559Y626848D03*
X625759D03*
X623559Y1077404D03*
X625759D03*
X623559Y1079604D03*
X625759D03*
X747772Y174092D03*
Y171892D03*
Y624648D03*
Y626848D03*
Y1077404D03*
Y1079604D03*
X749972Y174092D03*
Y171892D03*
Y624648D03*
Y626848D03*
Y1077404D03*
Y1079604D03*
G54D16*
X25000Y1195200D03*
X30000D03*
X95437Y290361D03*
Y743117D03*
Y1195873D03*
X135422Y1195737D03*
X140422D03*
X219649Y290361D03*
Y743117D03*
X259594Y1195568D03*
X264594D03*
X219649Y1195873D03*
X343862Y290361D03*
Y743117D03*
Y1195873D03*
X383849Y1195442D03*
X388849D03*
X468074Y290361D03*
Y743117D03*
X508103Y1195357D03*
X468074Y1195873D03*
X513103Y1195357D03*
X592287Y290361D03*
X584279Y567031D03*
X592287Y743117D03*
Y1195873D03*
X607460Y560974D03*
X632316Y1195274D03*
X637316D03*
X716500Y290361D03*
Y743117D03*
Y1195873D03*
X751209Y159828D03*
X752500Y1157700D03*
X881256Y1365150D03*
X933524Y922100D03*
X967813Y1553966D03*
X953500Y1553400D03*
X1211205Y1156394D03*
X1216205D03*
X1298500Y260361D03*
Y289861D03*
Y742617D03*
Y713117D03*
Y1165873D03*
Y1195373D03*
X1351321Y1156353D03*
X1346321D03*
X1422713Y260361D03*
Y289861D03*
X1426419Y526957D03*
X1422713Y742617D03*
Y713117D03*
Y1165873D03*
Y1195373D03*
X1470953Y1156227D03*
X1475953D03*
X1507037Y528103D03*
X1546925Y260361D03*
Y289861D03*
Y742617D03*
Y713117D03*
Y1165873D03*
Y1195373D03*
X1615552Y1156406D03*
X1620236D03*
X1671138Y260361D03*
Y289861D03*
Y742617D03*
Y713117D03*
Y1165873D03*
Y1195373D03*
X1760500Y725200D03*
X1723117Y1156353D03*
X1718117D03*
X1795350Y260361D03*
Y289861D03*
X1795468Y742794D03*
X1795350Y713117D03*
Y1165873D03*
Y1195373D03*
X1836400Y1155900D03*
X1841084Y1155921D03*
X1887169Y290361D03*
Y743117D03*
Y1195873D03*
G54D71*
X543338Y556769D03*
X567779Y574131D03*
X575779D03*
X588779D03*
X562279D03*
X876956Y1369350D03*
X929232Y925450D03*
X942879Y1365357D03*
X928194Y1376648D03*
X931500Y1560500D03*
X937000D03*
X973055Y1183053D03*
X945000Y1560500D03*
X958000D03*
X1032053Y-38475D03*
X999500Y1187800D03*
X1054625Y-43650D03*
X1320055Y75229D03*
X1436200Y553400D03*
X1459200Y575900D03*
X1598400Y1114800D03*
G54D35*
X72049Y374529D03*
X68109D03*
X72049Y368779D03*
X68109D03*
X72049Y827284D03*
X68109D03*
X72049Y821534D03*
X68109D03*
X72049Y1274290D03*
X68109D03*
X72049Y1280040D03*
X68109D03*
X196261Y374529D03*
X192321D03*
X196261Y368779D03*
X192321D03*
X196261Y827284D03*
X192321D03*
X196261Y821534D03*
X192321D03*
X196261Y1274290D03*
X192321D03*
X196261Y1280040D03*
X192321D03*
X320474Y374529D03*
X316534D03*
X320474Y368779D03*
X316534D03*
X320474Y827284D03*
X316534D03*
X320474Y821534D03*
X316534D03*
X320474Y1274290D03*
X316534D03*
X320474Y1280040D03*
X316534D03*
X444687Y374529D03*
X440747D03*
X444687Y368779D03*
X440747D03*
X444687Y827284D03*
X440747D03*
X444687Y821534D03*
X440747D03*
X444687Y1274290D03*
X440747D03*
X444687Y1280040D03*
X440747D03*
X568899Y374529D03*
X564959D03*
X568899Y368779D03*
X564959D03*
X568899Y827284D03*
X564959D03*
X568899Y821534D03*
X564959D03*
X568899Y1274290D03*
X564959D03*
X568899Y1280040D03*
X564959D03*
X693112Y374529D03*
X689172D03*
X693112Y368779D03*
X689172D03*
X693112Y827284D03*
X689172D03*
X693112Y821534D03*
X689172D03*
X693112Y1274290D03*
X689172D03*
X693112Y1280040D03*
X689172D03*
X1242718Y374529D03*
X1238778D03*
X1242718Y368779D03*
X1238778D03*
X1242718Y827284D03*
X1238778D03*
X1242718Y821534D03*
X1238778D03*
X1242718Y1274290D03*
X1238778D03*
X1242718Y1280040D03*
X1238778D03*
X1366931Y374529D03*
X1362991D03*
X1366931Y368779D03*
X1362991D03*
X1366931Y827284D03*
X1362991D03*
X1366931Y821534D03*
X1362991D03*
X1366931Y1274290D03*
X1362991D03*
X1366931Y1280040D03*
X1362991D03*
X1491143Y374529D03*
X1487203D03*
X1491143Y368779D03*
X1487203D03*
X1491143Y827284D03*
X1487203D03*
X1491143Y821534D03*
X1487203D03*
X1491143Y1274290D03*
X1487203D03*
X1491143Y1280040D03*
X1487203D03*
X1615356Y374529D03*
X1611416D03*
X1615356Y368779D03*
X1611416D03*
X1615356Y827284D03*
X1611416D03*
X1615356Y821534D03*
X1611416D03*
X1615356Y1274290D03*
X1611416D03*
X1615356Y1280040D03*
X1611416D03*
X1739568Y374529D03*
X1735628D03*
X1739568Y368779D03*
X1735628D03*
X1739568Y827284D03*
X1735628D03*
X1739568Y821534D03*
X1735628D03*
X1739568Y1274290D03*
X1735628D03*
X1739568Y1280040D03*
X1735628D03*
X1859841Y374529D03*
Y368779D03*
Y827284D03*
Y821534D03*
Y1274290D03*
Y1280040D03*
X1863781Y374529D03*
Y368779D03*
Y827284D03*
Y821534D03*
Y1274290D03*
Y1280040D03*
G54D44*
X118209Y195492D03*
Y190492D03*
Y185492D03*
Y180492D03*
Y175492D03*
Y170492D03*
Y165492D03*
Y260492D03*
Y255492D03*
Y250492D03*
Y245492D03*
Y240492D03*
Y235492D03*
Y230492D03*
Y225492D03*
Y220492D03*
Y290492D03*
Y285492D03*
Y280492D03*
Y275492D03*
Y270492D03*
Y265492D03*
Y648248D03*
Y643248D03*
Y638248D03*
Y633248D03*
Y628248D03*
Y623248D03*
Y618248D03*
Y693248D03*
Y688248D03*
Y683248D03*
Y678248D03*
Y673248D03*
Y743248D03*
Y738248D03*
Y733248D03*
Y728248D03*
Y723248D03*
Y718248D03*
Y713248D03*
Y708248D03*
Y703248D03*
Y698248D03*
Y1081004D03*
Y1076004D03*
Y1071004D03*
Y1131004D03*
Y1126004D03*
Y1101004D03*
Y1096004D03*
Y1091004D03*
Y1086004D03*
Y1176004D03*
Y1171004D03*
Y1166004D03*
Y1161004D03*
Y1156004D03*
Y1151004D03*
Y1146004D03*
Y1141004D03*
Y1136004D03*
Y1196004D03*
Y1191004D03*
Y1186004D03*
Y1181004D03*
X242421Y195492D03*
Y190492D03*
Y185492D03*
Y180492D03*
Y175492D03*
Y170492D03*
Y165492D03*
Y260492D03*
Y255492D03*
Y250492D03*
Y245492D03*
Y240492D03*
Y235492D03*
Y230492D03*
Y225492D03*
Y220492D03*
Y290492D03*
Y285492D03*
Y280492D03*
Y275492D03*
Y270492D03*
Y265492D03*
Y648248D03*
Y643248D03*
Y638248D03*
Y633248D03*
Y628248D03*
Y623248D03*
Y618248D03*
Y693248D03*
Y688248D03*
Y683248D03*
Y678248D03*
Y673248D03*
Y743248D03*
Y738248D03*
Y733248D03*
Y728248D03*
Y723248D03*
Y718248D03*
Y713248D03*
Y708248D03*
Y703248D03*
Y698248D03*
Y1081004D03*
Y1076004D03*
Y1071004D03*
Y1131004D03*
Y1126004D03*
Y1101004D03*
Y1096004D03*
Y1091004D03*
Y1086004D03*
Y1176004D03*
Y1171004D03*
Y1166004D03*
Y1161004D03*
Y1156004D03*
Y1151004D03*
Y1146004D03*
Y1141004D03*
Y1136004D03*
Y1196004D03*
Y1191004D03*
Y1186004D03*
Y1181004D03*
X366634Y195492D03*
Y190492D03*
Y185492D03*
Y180492D03*
Y175492D03*
Y170492D03*
Y165492D03*
Y260492D03*
Y255492D03*
Y250492D03*
Y245492D03*
Y240492D03*
Y235492D03*
Y230492D03*
Y225492D03*
Y220492D03*
Y290492D03*
Y285492D03*
Y280492D03*
Y275492D03*
Y270492D03*
Y265492D03*
Y648248D03*
Y643248D03*
Y638248D03*
Y633248D03*
Y628248D03*
Y623248D03*
Y618248D03*
Y693248D03*
Y688248D03*
Y683248D03*
Y678248D03*
Y673248D03*
Y743248D03*
Y738248D03*
Y733248D03*
Y728248D03*
Y723248D03*
Y718248D03*
Y713248D03*
Y708248D03*
Y703248D03*
Y698248D03*
Y1081004D03*
Y1076004D03*
Y1071004D03*
Y1131004D03*
Y1126004D03*
Y1101004D03*
Y1096004D03*
Y1091004D03*
Y1086004D03*
Y1176004D03*
Y1171004D03*
Y1166004D03*
Y1161004D03*
Y1156004D03*
Y1151004D03*
Y1146004D03*
Y1141004D03*
Y1136004D03*
Y1196004D03*
Y1191004D03*
Y1186004D03*
Y1181004D03*
X490846Y195492D03*
Y190492D03*
Y185492D03*
Y180492D03*
Y175492D03*
Y170492D03*
Y165492D03*
Y260492D03*
Y255492D03*
Y250492D03*
Y245492D03*
Y240492D03*
Y235492D03*
Y230492D03*
Y225492D03*
Y220492D03*
Y290492D03*
Y285492D03*
Y280492D03*
Y275492D03*
Y270492D03*
Y265492D03*
Y648248D03*
Y643248D03*
Y638248D03*
Y633248D03*
Y628248D03*
Y623248D03*
Y618248D03*
Y693248D03*
Y688248D03*
Y683248D03*
Y678248D03*
Y673248D03*
Y743248D03*
Y738248D03*
Y733248D03*
Y728248D03*
Y723248D03*
Y718248D03*
Y713248D03*
Y708248D03*
Y703248D03*
Y698248D03*
Y1081004D03*
Y1076004D03*
Y1071004D03*
Y1131004D03*
Y1126004D03*
Y1101004D03*
Y1096004D03*
Y1091004D03*
Y1086004D03*
Y1176004D03*
Y1171004D03*
Y1166004D03*
Y1161004D03*
Y1156004D03*
Y1151004D03*
Y1146004D03*
Y1141004D03*
Y1136004D03*
Y1196004D03*
Y1191004D03*
Y1186004D03*
Y1181004D03*
X615059Y195492D03*
Y190492D03*
Y185492D03*
Y180492D03*
Y175492D03*
Y170492D03*
Y165492D03*
Y260492D03*
Y255492D03*
Y250492D03*
Y245492D03*
Y240492D03*
Y235492D03*
Y230492D03*
Y225492D03*
Y220492D03*
Y290492D03*
Y285492D03*
Y280492D03*
Y275492D03*
Y270492D03*
Y265492D03*
Y648248D03*
Y643248D03*
Y638248D03*
Y633248D03*
Y628248D03*
Y623248D03*
Y618248D03*
Y693248D03*
Y688248D03*
Y683248D03*
Y678248D03*
Y673248D03*
Y743248D03*
Y738248D03*
Y733248D03*
Y728248D03*
Y723248D03*
Y718248D03*
Y713248D03*
Y708248D03*
Y703248D03*
Y698248D03*
Y1081004D03*
Y1076004D03*
Y1071004D03*
Y1131004D03*
Y1126004D03*
Y1101004D03*
Y1096004D03*
Y1091004D03*
Y1086004D03*
Y1176004D03*
Y1171004D03*
Y1166004D03*
Y1161004D03*
Y1156004D03*
Y1151004D03*
Y1146004D03*
Y1141004D03*
Y1136004D03*
Y1196004D03*
Y1191004D03*
Y1186004D03*
Y1181004D03*
X739272Y195492D03*
Y190492D03*
Y185492D03*
Y180492D03*
Y175492D03*
Y170492D03*
Y165492D03*
Y260492D03*
Y255492D03*
Y250492D03*
Y245492D03*
Y240492D03*
Y235492D03*
Y230492D03*
Y225492D03*
Y220492D03*
Y290492D03*
Y285492D03*
Y280492D03*
Y275492D03*
Y270492D03*
Y265492D03*
Y648248D03*
Y643248D03*
Y638248D03*
Y633248D03*
Y628248D03*
Y623248D03*
Y618248D03*
Y693248D03*
Y688248D03*
Y683248D03*
Y678248D03*
Y673248D03*
Y743248D03*
Y738248D03*
Y733248D03*
Y728248D03*
Y723248D03*
Y718248D03*
Y713248D03*
Y708248D03*
Y703248D03*
Y698248D03*
Y1081004D03*
Y1076004D03*
Y1071004D03*
Y1131004D03*
Y1126004D03*
Y1101004D03*
Y1096004D03*
Y1091004D03*
Y1086004D03*
Y1176004D03*
Y1171004D03*
Y1166004D03*
Y1161004D03*
Y1156004D03*
Y1151004D03*
Y1146004D03*
Y1141004D03*
Y1136004D03*
Y1196004D03*
Y1191004D03*
Y1186004D03*
Y1181004D03*
X1288878Y195492D03*
Y190492D03*
Y185492D03*
Y180492D03*
Y175492D03*
Y170492D03*
Y165492D03*
Y260492D03*
Y255492D03*
Y250492D03*
Y245492D03*
Y240492D03*
Y235492D03*
Y230492D03*
Y225492D03*
Y220492D03*
Y290492D03*
Y285492D03*
Y280492D03*
Y275492D03*
Y270492D03*
Y265492D03*
Y648248D03*
Y643248D03*
Y638248D03*
Y633248D03*
Y628248D03*
Y623248D03*
Y618248D03*
Y693248D03*
Y688248D03*
Y683248D03*
Y678248D03*
Y673248D03*
Y743248D03*
Y738248D03*
Y733248D03*
Y728248D03*
Y723248D03*
Y718248D03*
Y713248D03*
Y708248D03*
Y703248D03*
Y698248D03*
Y1081004D03*
Y1076004D03*
Y1071004D03*
Y1131004D03*
Y1126004D03*
Y1101004D03*
Y1096004D03*
Y1091004D03*
Y1086004D03*
Y1176004D03*
Y1171004D03*
Y1166004D03*
Y1161004D03*
Y1156004D03*
Y1151004D03*
Y1146004D03*
Y1141004D03*
Y1136004D03*
Y1196004D03*
Y1191004D03*
Y1186004D03*
Y1181004D03*
X1413091Y195492D03*
Y190492D03*
Y185492D03*
Y180492D03*
Y175492D03*
Y170492D03*
Y165492D03*
Y260492D03*
Y255492D03*
Y250492D03*
Y245492D03*
Y240492D03*
Y235492D03*
Y230492D03*
Y225492D03*
Y220492D03*
Y290492D03*
Y285492D03*
Y280492D03*
Y275492D03*
Y270492D03*
Y265492D03*
Y648248D03*
Y643248D03*
Y638248D03*
Y633248D03*
Y628248D03*
Y623248D03*
Y618248D03*
Y693248D03*
Y688248D03*
Y683248D03*
Y678248D03*
Y673248D03*
Y743248D03*
Y738248D03*
Y733248D03*
Y728248D03*
Y723248D03*
Y718248D03*
Y713248D03*
Y708248D03*
Y703248D03*
Y698248D03*
Y1081004D03*
Y1076004D03*
Y1071004D03*
Y1131004D03*
Y1126004D03*
Y1101004D03*
Y1096004D03*
Y1091004D03*
Y1086004D03*
Y1176004D03*
Y1171004D03*
Y1166004D03*
Y1161004D03*
Y1156004D03*
Y1151004D03*
Y1146004D03*
Y1141004D03*
Y1136004D03*
Y1196004D03*
Y1191004D03*
Y1186004D03*
Y1181004D03*
X1537303Y195492D03*
Y190492D03*
Y185492D03*
Y180492D03*
Y175492D03*
Y170492D03*
Y165492D03*
Y260492D03*
Y255492D03*
Y250492D03*
Y245492D03*
Y240492D03*
Y235492D03*
Y230492D03*
Y225492D03*
Y220492D03*
Y290492D03*
Y285492D03*
Y280492D03*
Y275492D03*
Y270492D03*
Y265492D03*
Y648248D03*
Y643248D03*
Y638248D03*
Y633248D03*
Y628248D03*
Y623248D03*
Y618248D03*
Y693248D03*
Y688248D03*
Y683248D03*
Y678248D03*
Y673248D03*
Y743248D03*
Y738248D03*
Y733248D03*
Y728248D03*
Y723248D03*
Y718248D03*
Y713248D03*
Y708248D03*
Y703248D03*
Y698248D03*
Y1081004D03*
Y1076004D03*
Y1071004D03*
Y1131004D03*
Y1126004D03*
Y1101004D03*
Y1096004D03*
Y1091004D03*
Y1086004D03*
Y1176004D03*
Y1171004D03*
Y1166004D03*
Y1161004D03*
Y1156004D03*
Y1151004D03*
Y1146004D03*
Y1141004D03*
Y1136004D03*
Y1196004D03*
Y1191004D03*
Y1186004D03*
Y1181004D03*
X1661516Y195492D03*
Y190492D03*
Y185492D03*
Y180492D03*
Y175492D03*
Y170492D03*
Y165492D03*
Y260492D03*
Y255492D03*
Y250492D03*
Y245492D03*
Y240492D03*
Y235492D03*
Y230492D03*
Y225492D03*
Y220492D03*
Y290492D03*
Y285492D03*
Y280492D03*
Y275492D03*
Y270492D03*
Y265492D03*
Y648248D03*
Y643248D03*
Y638248D03*
Y633248D03*
Y628248D03*
Y623248D03*
Y618248D03*
Y693248D03*
Y688248D03*
Y683248D03*
Y678248D03*
Y673248D03*
Y743248D03*
Y738248D03*
Y733248D03*
Y728248D03*
Y723248D03*
Y718248D03*
Y713248D03*
Y708248D03*
Y703248D03*
Y698248D03*
Y1081004D03*
Y1076004D03*
Y1071004D03*
Y1131004D03*
Y1126004D03*
Y1101004D03*
Y1096004D03*
Y1091004D03*
Y1086004D03*
Y1176004D03*
Y1171004D03*
Y1166004D03*
Y1161004D03*
Y1156004D03*
Y1151004D03*
Y1146004D03*
Y1141004D03*
Y1136004D03*
Y1196004D03*
Y1191004D03*
Y1186004D03*
Y1181004D03*
X1785728Y195492D03*
Y190492D03*
Y185492D03*
Y180492D03*
Y175492D03*
Y170492D03*
Y165492D03*
Y260492D03*
Y255492D03*
Y250492D03*
Y245492D03*
Y240492D03*
Y235492D03*
Y230492D03*
Y225492D03*
Y220492D03*
Y290492D03*
Y285492D03*
Y280492D03*
Y275492D03*
Y270492D03*
Y265492D03*
Y648248D03*
Y643248D03*
Y638248D03*
Y633248D03*
Y628248D03*
Y623248D03*
Y618248D03*
Y693248D03*
Y688248D03*
Y683248D03*
Y678248D03*
Y673248D03*
Y743248D03*
Y738248D03*
Y733248D03*
Y728248D03*
Y723248D03*
Y718248D03*
Y713248D03*
Y708248D03*
Y703248D03*
Y698248D03*
Y1081004D03*
Y1076004D03*
Y1071004D03*
Y1131004D03*
Y1126004D03*
Y1101004D03*
Y1096004D03*
Y1091004D03*
Y1086004D03*
Y1176004D03*
Y1171004D03*
Y1166004D03*
Y1161004D03*
Y1156004D03*
Y1151004D03*
Y1146004D03*
Y1141004D03*
Y1136004D03*
Y1196004D03*
Y1191004D03*
Y1186004D03*
Y1181004D03*
X1909941Y195492D03*
Y190492D03*
Y185492D03*
Y180492D03*
Y175492D03*
Y170492D03*
Y165492D03*
Y260492D03*
Y255492D03*
Y250492D03*
Y245492D03*
Y240492D03*
Y235492D03*
Y230492D03*
Y225492D03*
Y220492D03*
Y290492D03*
Y285492D03*
Y280492D03*
Y275492D03*
Y270492D03*
Y265492D03*
Y648248D03*
Y643248D03*
Y638248D03*
Y633248D03*
Y628248D03*
Y623248D03*
Y618248D03*
Y693248D03*
Y688248D03*
Y683248D03*
Y678248D03*
Y673248D03*
Y743248D03*
Y738248D03*
Y733248D03*
Y728248D03*
Y723248D03*
Y718248D03*
Y713248D03*
Y708248D03*
Y703248D03*
Y698248D03*
Y1081004D03*
Y1076004D03*
Y1071004D03*
Y1131004D03*
Y1126004D03*
Y1101004D03*
Y1096004D03*
Y1091004D03*
Y1086004D03*
Y1176004D03*
Y1171004D03*
Y1166004D03*
Y1161004D03*
Y1156004D03*
Y1151004D03*
Y1146004D03*
Y1141004D03*
Y1136004D03*
Y1196004D03*
Y1191004D03*
Y1186004D03*
Y1181004D03*
G54D80*
X683341Y586324D03*
X689747D03*
G54D53*
X139637Y256161D03*
Y708917D03*
Y1161673D03*
X263849Y256161D03*
Y708917D03*
Y1161673D03*
X388062Y256161D03*
Y708917D03*
X387862Y1161673D03*
X500074Y1130873D03*
X512274Y256161D03*
Y708917D03*
X525874Y1152773D03*
X636487Y256161D03*
Y708917D03*
Y1161673D03*
X827508Y37372D03*
X862777Y37234D03*
X932209Y991763D03*
X909282Y1534500D03*
X1107500Y-48400D03*
X1429400Y544600D03*
X1454461Y588256D03*
X1498082Y539100D03*
X1881532Y1054227D03*
G54D26*
X60137Y210561D03*
X61784Y513020D03*
X47557Y513016D03*
X60137Y663317D03*
Y1116073D03*
X92137Y176661D03*
Y181161D03*
Y633917D03*
X104263Y985725D03*
X120397Y995001D03*
X105563Y1003325D03*
X92237Y1082173D03*
Y1086673D03*
X142637Y244761D03*
Y697517D03*
X140563Y1005625D03*
X128763Y1001725D03*
X140522Y997250D03*
X127855Y992723D03*
X142637Y1150273D03*
X184349Y210561D03*
X216449Y181361D03*
Y176661D03*
X186038Y512878D03*
X171811Y512874D03*
X207263Y593625D03*
X195463Y589725D03*
X207222Y585250D03*
X187097Y583001D03*
X194555Y580723D03*
X172263Y591025D03*
X170963Y573725D03*
X216449Y623417D03*
Y618917D03*
X206200Y650000D03*
X190099Y667589D03*
X216449Y1082173D03*
Y1086873D03*
X190149Y1119573D03*
X308562Y210561D03*
X266849Y244761D03*
X310209Y512878D03*
X295982Y512874D03*
X308562Y663317D03*
X266849Y697517D03*
X308562Y1116073D03*
X266849Y1150273D03*
X319121Y72855D03*
X329479Y72845D03*
X340762Y176461D03*
X340662Y181161D03*
Y634017D03*
X340762Y1082073D03*
Y1086773D03*
X391062Y244761D03*
Y697517D03*
Y1150273D03*
X432774Y210561D03*
X434359Y512841D03*
X420132Y512837D03*
X432774Y663317D03*
X453374Y1112973D03*
X447373Y1091326D03*
X464874Y176461D03*
Y181161D03*
Y633917D03*
X503274Y1145973D03*
X515274Y244661D03*
X545079Y528531D03*
Y532831D03*
X528677Y512878D03*
X514450Y512874D03*
X547579Y566531D03*
Y561531D03*
X515274Y697417D03*
X589087Y176661D03*
Y181361D03*
X556987Y210661D03*
X604979Y538831D03*
Y542831D03*
X579479Y566331D03*
X571479D03*
X598979Y552331D03*
X589087Y634017D03*
Y629417D03*
X556987Y663417D03*
X589087Y1082173D03*
Y1086873D03*
X556987Y1116173D03*
X625097Y107633D03*
X615101Y112329D03*
X639487Y244761D03*
X642084Y512541D03*
X627857Y512537D03*
X619510Y562574D03*
Y555174D03*
X639487Y697517D03*
Y1150273D03*
X681200Y210561D03*
X681700Y665817D03*
X687000Y1119973D03*
X713300Y176461D03*
Y181161D03*
Y633917D03*
Y629417D03*
Y1081973D03*
Y1086673D03*
X752900Y205500D03*
X751700Y677700D03*
X842400Y1538800D03*
X878250Y359100D03*
X878054Y445462D03*
X878100Y450200D03*
Y454900D03*
X878200Y471100D03*
X878154Y459562D03*
X878143Y464505D03*
X879343Y542405D03*
X889303Y856727D03*
X872072Y1358528D03*
X881312Y1380412D03*
X881311Y1375746D03*
X871908Y1523720D03*
X910300Y1512600D03*
Y1508100D03*
X940700Y1552700D03*
X919700Y1539200D03*
X916700Y1544200D03*
X972090Y1153500D03*
X948700Y1552700D03*
X979913Y1553466D03*
Y1549366D03*
X968232Y1538282D03*
X971200Y1529200D03*
Y1525200D03*
X1019032Y-66200D03*
X1007532Y-43500D03*
X1014850Y550000D03*
X1028635Y908603D03*
X1028600Y904200D03*
X1013200Y930500D03*
X1038074Y1354526D03*
X1042258Y-71536D03*
X1065521Y-76578D03*
X1066304Y79465D03*
X1049700Y442000D03*
X1049737Y429753D03*
X1049701Y434409D03*
X1049915Y557053D03*
X1113300Y-89600D03*
X1113321Y-85538D03*
X1104279Y-82462D03*
X1224910Y236291D03*
X1198050Y284750D03*
X1197829Y1033731D03*
Y1029031D03*
X1253461Y513463D03*
X1239324Y513432D03*
X1258200Y697850D03*
X1253925Y966004D03*
X1239776Y965973D03*
X1258200Y1150173D03*
X1311700Y191161D03*
Y643917D03*
Y1096673D03*
X1335200Y223661D03*
X1349813Y513334D03*
X1335676Y513303D03*
X1335200Y676417D03*
X1352246Y965705D03*
X1338205Y965825D03*
X1335200Y1129173D03*
X1384409Y244829D03*
X1435913Y191161D03*
X1459413Y223661D03*
X1438900Y526100D03*
X1435913Y643917D03*
X1459413Y676417D03*
X1462417Y965883D03*
X1459413Y1129173D03*
X1435913Y1096673D03*
X1476458Y965763D03*
X1560125Y191161D03*
X1555125Y645917D03*
X1552525Y1132273D03*
X1583625Y223661D03*
X1600695Y513418D03*
X1586558Y513387D03*
X1583625Y676417D03*
X1600771Y965889D03*
X1586630Y965809D03*
X1684338Y191161D03*
X1707838Y223661D03*
X1711023Y513134D03*
X1684338Y643917D03*
X1707838Y676417D03*
X1684338Y1096673D03*
X1707838Y1129173D03*
X1725160Y513165D03*
X1763200Y720500D03*
X1763334Y965756D03*
X1749136Y965664D03*
X1762197Y1007001D03*
X1747363Y1015325D03*
X1746063Y997725D03*
X1808550Y191161D03*
Y643917D03*
X1806027Y965626D03*
X1793838Y968689D03*
X1770563Y1013725D03*
X1782322Y1009250D03*
X1769655Y1004723D03*
X1782363Y1017625D03*
X1808550Y1096673D03*
X1851869Y210461D03*
X1845517Y181175D03*
X1832050Y223661D03*
X1848995Y513292D03*
X1834858Y513261D03*
X1845617Y633931D03*
X1832050Y676417D03*
X1851869Y663317D03*
X1831650Y1128973D03*
X1858406Y1113294D03*
X1884785Y1059938D03*
G54D17*
X35506Y-110687D03*
X63128Y89671D03*
X60754Y1316385D03*
X72380Y1596505D03*
X1861177Y91072D03*
X1874818Y-110232D03*
G54D62*
X429724Y63977D03*
X443898D03*
X458071D03*
X436811Y67914D03*
X450984D03*
X429724Y116339D03*
Y92323D03*
Y96654D03*
Y102166D03*
Y106496D03*
Y110827D03*
Y78150D03*
X443898Y116339D03*
X458071D03*
X436811Y114764D03*
X450984D03*
X436811Y82087D03*
X450984D03*
X443898Y92323D03*
X458071D03*
X443898Y96654D03*
X458071D03*
X436811Y96260D03*
X450984D03*
X443898Y102166D03*
X458071D03*
X436811Y100591D03*
X450984D03*
X443898Y106496D03*
X458071D03*
X436811Y106103D03*
X450984D03*
X443898Y110827D03*
X458071D03*
X436811Y110433D03*
X450984D03*
X443898Y78150D03*
X458071D03*
X429724Y120670D03*
X443898D03*
X458071D03*
X436811Y120276D03*
X450984D03*
X465157Y67914D03*
X472244Y63977D03*
X479331Y67914D03*
X465157Y114764D03*
X472244Y116339D03*
X479331Y114764D03*
X465157Y82087D03*
Y96260D03*
Y100591D03*
Y106103D03*
Y110433D03*
X479331Y82087D03*
X472244Y92323D03*
Y96654D03*
X479331Y96260D03*
X472244Y102166D03*
X479331Y100591D03*
X472244Y106496D03*
X479331Y106103D03*
X472244Y110827D03*
X479331Y110433D03*
X472244Y78150D03*
X465157Y120276D03*
X472244Y120670D03*
X479331Y120276D03*
X514764Y63977D03*
X550197Y67914D03*
X536024D03*
X521850D03*
X543110Y63977D03*
X528937D03*
X557283D03*
X514764Y116339D03*
Y110827D03*
Y106496D03*
Y102166D03*
Y96654D03*
Y92323D03*
Y78150D03*
X550197Y114764D03*
X536024D03*
X521850D03*
X543110Y116339D03*
X528937D03*
X550197Y110433D03*
X536024D03*
X521850D03*
X543110Y110827D03*
X528937D03*
X550197Y106103D03*
X536024D03*
X521850D03*
X543110Y106496D03*
X528937D03*
X550197Y100591D03*
X536024D03*
X521850D03*
X543110Y102166D03*
X528937D03*
X550197Y96260D03*
X536024D03*
X521850D03*
X543110Y96654D03*
X528937D03*
X543110Y92323D03*
X528937D03*
X550197Y82087D03*
X536024D03*
X521850D03*
X543110Y78150D03*
X528937D03*
X557283Y116339D03*
Y110827D03*
Y106496D03*
Y102166D03*
Y96654D03*
Y92323D03*
Y78150D03*
X514764Y120670D03*
X550197Y120276D03*
X536024D03*
X521850D03*
X543110Y120670D03*
X528937D03*
X557283D03*
X564370Y67914D03*
Y114764D03*
Y110433D03*
Y106103D03*
Y100591D03*
Y96260D03*
Y82087D03*
Y120276D03*
X833859Y1594095D03*
Y1598425D03*
Y1603937D03*
Y1608268D03*
Y1612599D03*
X840945Y1598032D03*
X826772D03*
X840945Y1602363D03*
X826772D03*
X840945Y1607874D03*
X826772D03*
X840945Y1612205D03*
X826772D03*
X840945Y1616536D03*
X826772D03*
X833859Y1618111D03*
Y1622441D03*
Y1626772D03*
Y1632284D03*
Y1636614D03*
Y1640945D03*
Y1646457D03*
Y1650788D03*
X840945Y1622048D03*
X826772D03*
X840945Y1626378D03*
X826772D03*
X840945Y1630709D03*
X826772D03*
X840945Y1636221D03*
X826772D03*
X840945Y1640551D03*
X826772D03*
X840945Y1644882D03*
X826772D03*
X840945Y1650394D03*
X826772D03*
X876378Y1594095D03*
X862205D03*
X848032D03*
X876378Y1598425D03*
X862205D03*
X848032D03*
X876378Y1603937D03*
X862205D03*
X848032D03*
X876378Y1608268D03*
X862205D03*
X848032D03*
X876378Y1612599D03*
X862205D03*
X848032D03*
X890552Y1598032D03*
X869292D03*
X855118D03*
X890552Y1602363D03*
X869292D03*
X855118D03*
X890552Y1607874D03*
X869292D03*
X855118D03*
X890552Y1612205D03*
X869292D03*
X855118D03*
X890552Y1616536D03*
X869292D03*
X855118D03*
X876378Y1618111D03*
X862205D03*
X848032D03*
X876378Y1622441D03*
X862205D03*
X848032D03*
X876378Y1626772D03*
X862205D03*
X848032D03*
X876378Y1632284D03*
X862205D03*
X848032D03*
X876378Y1636614D03*
X862205D03*
X848032D03*
X876378Y1640945D03*
X862205D03*
X848032D03*
X876378Y1646457D03*
X862205D03*
X848032D03*
X876378Y1650788D03*
X862205D03*
X848032D03*
X890552Y1622048D03*
X869292D03*
X855118D03*
X890552Y1626378D03*
X869292D03*
X855118D03*
X890552Y1630709D03*
X869292D03*
X855118D03*
X890552Y1636221D03*
X869292D03*
X855118D03*
X890552Y1640551D03*
X869292D03*
X855118D03*
X890552Y1644882D03*
X869292D03*
X855118D03*
X890552Y1650394D03*
X869292D03*
X855118D03*
X911811Y1603937D03*
Y1608268D03*
Y1612599D03*
X904725Y1602363D03*
Y1607874D03*
Y1612205D03*
Y1616536D03*
X911811Y1594095D03*
Y1598425D03*
X904725Y1598032D03*
X897638Y1594095D03*
Y1598425D03*
Y1603937D03*
Y1608268D03*
Y1612599D03*
X911811Y1632284D03*
Y1636614D03*
Y1640945D03*
Y1646457D03*
Y1650788D03*
X904725Y1630709D03*
Y1636221D03*
Y1640551D03*
Y1644882D03*
Y1650394D03*
X911811Y1618111D03*
Y1622441D03*
Y1626772D03*
X904725Y1622048D03*
Y1626378D03*
X897638Y1618111D03*
Y1622441D03*
Y1626772D03*
Y1632284D03*
Y1636614D03*
Y1640945D03*
Y1646457D03*
Y1650788D03*
X1091089Y988592D03*
X1095420D03*
X1100932D03*
X1105262D03*
X1109593D03*
X1115105D03*
X1119435D03*
X1123766D03*
X1129278D03*
X1133609D03*
X1095026Y995678D03*
X1099357D03*
X1104869D03*
X1109199D03*
X1113530D03*
X1119042D03*
X1123372D03*
X1127703D03*
X1133215D03*
X1091089Y1002765D03*
X1095420D03*
X1100932D03*
X1105262D03*
X1109593D03*
X1115105D03*
X1119435D03*
X1123766D03*
X1129278D03*
X1133609D03*
X1095026Y1009852D03*
X1099357D03*
X1104869D03*
X1109199D03*
X1113530D03*
X1119042D03*
X1123372D03*
X1127703D03*
X1133215D03*
X1091089Y1016938D03*
X1095420D03*
X1100932D03*
X1105262D03*
X1109593D03*
X1115105D03*
X1119435D03*
X1123766D03*
X1129278D03*
X1133609D03*
X1095026Y1024025D03*
X1099357D03*
X1104869D03*
X1109199D03*
X1113530D03*
X1119042D03*
X1123372D03*
X1127703D03*
X1133215D03*
X1091089Y1031111D03*
X1095420D03*
X1100932D03*
X1105262D03*
X1109593D03*
X1115105D03*
X1119435D03*
X1123766D03*
X1129278D03*
X1133609D03*
X1095026Y1038198D03*
X1099357D03*
X1104869D03*
X1109199D03*
X1113530D03*
X1119042D03*
X1123372D03*
X1127703D03*
X1133215D03*
X1091089Y1160257D03*
Y1174430D03*
X1095420Y1160257D03*
Y1174430D03*
X1100932Y1160257D03*
Y1174430D03*
X1105262Y1160257D03*
Y1174430D03*
X1109593Y1160257D03*
Y1174430D03*
X1115105Y1160257D03*
Y1174430D03*
X1119435Y1160257D03*
Y1174430D03*
X1123766Y1160257D03*
Y1174430D03*
X1129278Y1160257D03*
Y1174430D03*
X1133609Y1160257D03*
Y1174430D03*
X1095026Y1167343D03*
X1099357D03*
X1104869D03*
X1109199D03*
X1113530D03*
X1119042D03*
X1123372D03*
X1127703D03*
X1133215D03*
X1091089Y1188603D03*
Y1202776D03*
Y1216949D03*
X1095420Y1188603D03*
Y1202776D03*
Y1216949D03*
X1100932Y1188603D03*
Y1202776D03*
Y1216949D03*
X1105262Y1188603D03*
Y1202776D03*
Y1216949D03*
X1109593Y1188603D03*
Y1202776D03*
Y1216949D03*
X1115105Y1188603D03*
Y1202776D03*
Y1216949D03*
X1119435Y1188603D03*
Y1202776D03*
Y1216949D03*
X1123766Y1188603D03*
Y1202776D03*
Y1216949D03*
X1129278Y1188603D03*
Y1202776D03*
Y1216949D03*
X1133609Y1188603D03*
Y1202776D03*
Y1216949D03*
X1095026Y1181516D03*
Y1195690D03*
Y1209863D03*
Y1224036D03*
X1099357Y1181516D03*
Y1195690D03*
Y1209863D03*
Y1224036D03*
X1104869Y1181516D03*
Y1195690D03*
Y1209863D03*
Y1224036D03*
X1109199Y1181516D03*
Y1195690D03*
Y1209863D03*
Y1224036D03*
X1113530Y1181516D03*
Y1195690D03*
Y1209863D03*
Y1224036D03*
X1119042Y1181516D03*
Y1195690D03*
Y1209863D03*
Y1224036D03*
X1123372Y1181516D03*
Y1195690D03*
Y1209863D03*
Y1224036D03*
X1127703Y1181516D03*
Y1195690D03*
Y1209863D03*
Y1224036D03*
X1133215Y1181516D03*
Y1195690D03*
Y1209863D03*
Y1224036D03*
X1091089Y1231123D03*
Y1245296D03*
Y1259469D03*
Y1273642D03*
X1095420Y1231123D03*
Y1245296D03*
Y1259469D03*
Y1273642D03*
X1100932Y1231123D03*
Y1245296D03*
Y1259469D03*
Y1273642D03*
X1105262Y1231123D03*
Y1245296D03*
Y1259469D03*
Y1273642D03*
X1109593Y1231123D03*
Y1245296D03*
Y1259469D03*
Y1273642D03*
X1115105Y1231123D03*
Y1245296D03*
Y1259469D03*
Y1273642D03*
X1119435Y1231123D03*
Y1245296D03*
Y1259469D03*
Y1273642D03*
X1123766Y1231123D03*
Y1245296D03*
Y1259469D03*
Y1273642D03*
X1129278Y1231123D03*
Y1245296D03*
Y1259469D03*
Y1273642D03*
X1133609Y1231123D03*
Y1245296D03*
Y1259469D03*
Y1273642D03*
X1095026Y1238209D03*
Y1252382D03*
Y1266556D03*
X1099357Y1238209D03*
Y1252382D03*
Y1266556D03*
X1104869Y1238209D03*
Y1252382D03*
Y1266556D03*
X1109199Y1238209D03*
Y1252382D03*
Y1266556D03*
X1113530Y1238209D03*
Y1252382D03*
Y1266556D03*
X1119042Y1238209D03*
Y1252382D03*
Y1266556D03*
X1123372Y1238209D03*
Y1252382D03*
Y1266556D03*
X1127703Y1238209D03*
Y1252382D03*
Y1266556D03*
X1133215Y1238209D03*
Y1252382D03*
Y1266556D03*
X1091089Y1287816D03*
Y1301989D03*
Y1316162D03*
X1095420Y1287816D03*
Y1301989D03*
Y1316162D03*
X1100932Y1287816D03*
Y1301989D03*
Y1316162D03*
X1105262Y1287816D03*
Y1301989D03*
Y1316162D03*
X1109593Y1287816D03*
Y1301989D03*
Y1316162D03*
X1115105Y1287816D03*
Y1301989D03*
Y1316162D03*
X1119435Y1287816D03*
Y1301989D03*
Y1316162D03*
X1123766Y1287816D03*
Y1301989D03*
Y1316162D03*
X1129278Y1287816D03*
Y1301989D03*
Y1316162D03*
X1133609Y1287816D03*
Y1301989D03*
Y1316162D03*
X1095026Y1280729D03*
Y1294902D03*
Y1309075D03*
Y1323249D03*
X1099357Y1280729D03*
Y1294902D03*
Y1309075D03*
Y1323249D03*
X1104869Y1280729D03*
Y1294902D03*
Y1309075D03*
Y1323249D03*
X1109199Y1280729D03*
Y1294902D03*
Y1309075D03*
Y1323249D03*
X1113530Y1280729D03*
Y1294902D03*
Y1309075D03*
Y1323249D03*
X1119042Y1280729D03*
Y1294902D03*
Y1309075D03*
Y1323249D03*
X1123372Y1280729D03*
Y1294902D03*
Y1309075D03*
Y1323249D03*
X1127703Y1280729D03*
Y1294902D03*
Y1309075D03*
Y1323249D03*
X1133215Y1280729D03*
Y1294902D03*
Y1309075D03*
Y1323249D03*
X1091089Y1330335D03*
Y1344508D03*
Y1358682D03*
Y1372855D03*
X1095420Y1330335D03*
Y1344508D03*
Y1358682D03*
Y1372855D03*
X1100932Y1330335D03*
Y1344508D03*
Y1358682D03*
Y1372855D03*
X1105262Y1330335D03*
Y1344508D03*
Y1358682D03*
Y1372855D03*
X1109593Y1330335D03*
Y1344508D03*
Y1358682D03*
Y1372855D03*
X1115105Y1330335D03*
Y1344508D03*
Y1358682D03*
Y1372855D03*
X1119435Y1330335D03*
Y1344508D03*
Y1358682D03*
Y1372855D03*
X1123766Y1330335D03*
Y1344508D03*
Y1358682D03*
Y1372855D03*
X1129278Y1330335D03*
Y1344508D03*
Y1358682D03*
Y1372855D03*
X1133609Y1330335D03*
Y1344508D03*
Y1358682D03*
Y1372855D03*
X1095026Y1337422D03*
Y1351595D03*
Y1365768D03*
X1099357Y1337422D03*
Y1351595D03*
Y1365768D03*
X1104869Y1337422D03*
Y1351595D03*
Y1365768D03*
X1109199Y1337422D03*
Y1351595D03*
Y1365768D03*
X1113530Y1337422D03*
Y1351595D03*
Y1365768D03*
X1119042Y1337422D03*
Y1351595D03*
Y1365768D03*
X1123372Y1337422D03*
Y1351595D03*
Y1365768D03*
X1127703Y1337422D03*
Y1351595D03*
Y1365768D03*
X1133215Y1337422D03*
Y1351595D03*
Y1365768D03*
X1091089Y1387028D03*
Y1401201D03*
X1095420Y1387028D03*
Y1401201D03*
X1100932Y1387028D03*
Y1401201D03*
X1105262Y1387028D03*
Y1401201D03*
X1109593Y1387028D03*
Y1401201D03*
X1115105Y1387028D03*
Y1401201D03*
X1119435Y1387028D03*
Y1401201D03*
X1123766Y1387028D03*
Y1401201D03*
X1129278Y1387028D03*
Y1401201D03*
X1133609Y1387028D03*
Y1401201D03*
X1095026Y1379942D03*
Y1394115D03*
Y1408288D03*
X1099357Y1379942D03*
Y1394115D03*
Y1408288D03*
X1104869Y1379942D03*
Y1394115D03*
Y1408288D03*
X1109199Y1379942D03*
Y1394115D03*
Y1408288D03*
X1113530Y1379942D03*
Y1394115D03*
Y1408288D03*
X1119042Y1379942D03*
Y1394115D03*
Y1408288D03*
X1123372Y1379942D03*
Y1394115D03*
Y1408288D03*
X1127703Y1379942D03*
Y1394115D03*
Y1408288D03*
X1133215Y1379942D03*
Y1394115D03*
Y1408288D03*
X1398228Y63977D03*
X1412402D03*
X1426575D03*
X1405315Y67914D03*
X1419488D03*
X1398228Y116339D03*
Y92323D03*
Y96654D03*
Y102166D03*
Y106496D03*
Y110827D03*
Y78150D03*
X1412402Y116339D03*
X1426575D03*
X1405315Y114764D03*
X1419488D03*
X1405315Y82087D03*
X1419488D03*
X1412402Y92323D03*
X1426575D03*
X1412402Y96654D03*
X1426575D03*
X1405315Y96260D03*
X1419488D03*
X1412402Y102166D03*
X1426575D03*
X1405315Y100591D03*
X1419488D03*
X1412402Y106496D03*
X1426575D03*
X1405315Y106103D03*
X1419488D03*
X1412402Y110827D03*
X1426575D03*
X1405315Y110433D03*
X1419488D03*
X1412402Y78150D03*
X1426575D03*
X1398228Y120670D03*
X1412402D03*
X1426575D03*
X1405315Y120276D03*
X1419488D03*
X1433661Y67914D03*
X1440748Y63977D03*
X1447835Y67914D03*
X1433661Y114764D03*
X1440748Y116339D03*
X1447835Y114764D03*
X1433661Y82087D03*
Y96260D03*
Y100591D03*
Y106103D03*
Y110433D03*
X1447835Y82087D03*
X1440748Y92323D03*
Y96654D03*
X1447835Y96260D03*
X1440748Y102166D03*
X1447835Y100591D03*
X1440748Y106496D03*
X1447835Y106103D03*
X1440748Y110827D03*
X1447835Y110433D03*
X1440748Y78150D03*
X1433661Y120276D03*
X1440748Y120670D03*
X1447835Y120276D03*
X1483268Y63977D03*
X1518701Y67914D03*
X1504528D03*
X1490354D03*
X1511614Y63977D03*
X1497441D03*
X1483268Y116339D03*
Y110827D03*
Y106496D03*
Y102166D03*
Y96654D03*
Y92323D03*
Y78150D03*
X1518701Y114764D03*
X1504528D03*
X1490354D03*
X1511614Y116339D03*
X1497441D03*
X1518701Y110433D03*
X1504528D03*
X1490354D03*
X1511614Y110827D03*
X1497441D03*
X1518701Y106103D03*
X1504528D03*
X1490354D03*
X1511614Y106496D03*
X1497441D03*
X1518701Y100591D03*
X1504528D03*
X1490354D03*
X1511614Y102166D03*
X1497441D03*
X1518701Y96260D03*
X1504528D03*
X1490354D03*
X1511614Y96654D03*
X1497441D03*
X1511614Y92323D03*
X1497441D03*
X1518701Y82087D03*
X1504528D03*
X1490354D03*
X1511614Y78150D03*
X1497441D03*
X1483268Y120670D03*
X1518701Y120276D03*
X1504528D03*
X1490354D03*
X1511614Y120670D03*
X1497441D03*
X1532874Y67914D03*
X1525787Y63977D03*
X1532874Y114764D03*
X1525787Y116339D03*
X1532874Y110433D03*
X1525787Y110827D03*
X1532874Y106103D03*
X1525787Y106496D03*
X1532874Y100591D03*
X1525787Y102166D03*
X1532874Y96260D03*
X1525787Y96654D03*
Y92323D03*
X1532874Y82087D03*
X1525787Y78150D03*
X1532874Y120276D03*
X1525787Y120670D03*
G54D90*
X944881Y-58267D03*
G54D36*
X43728Y499434D03*
X57963Y499397D03*
X47603Y506934D03*
X39853D03*
X61838Y506897D03*
X54088D03*
X167982Y499392D03*
X164107Y506892D03*
X182217Y499355D03*
X171857Y506892D03*
X186092Y506855D03*
X178342D03*
X292153Y499392D03*
X306388Y499355D03*
X296028Y506892D03*
X288278D03*
X310263Y506855D03*
X302513D03*
X416303Y499355D03*
X430538Y499318D03*
X420178Y506855D03*
X412428D03*
X434413Y506818D03*
X426663D03*
X506746Y506892D03*
X510621Y499392D03*
X524856Y499355D03*
X514496Y506892D03*
X528731Y506855D03*
X520981D03*
X624028Y499055D03*
X638263Y499018D03*
X627903Y506555D03*
X620153D03*
X642138Y506518D03*
X634388D03*
X858500Y1511250D03*
X862375Y1518750D03*
X854625D03*
X868458Y1529687D03*
X872333Y1537187D03*
X864583D03*
X937399Y897695D03*
X941274Y905195D03*
X933524D03*
X1239758Y499401D03*
X1253867Y499400D03*
X1243633Y506901D03*
X1235883D03*
X1257742Y506900D03*
X1249992D03*
X1240222Y951942D03*
X1244097Y959442D03*
X1236347D03*
X1254331Y951941D03*
X1258206Y959441D03*
X1250456D03*
X1336110Y499272D03*
X1350219Y499271D03*
X1339985Y506772D03*
X1332235D03*
X1354094Y506771D03*
X1346344D03*
X1338611Y952153D03*
X1342486Y959653D03*
X1334736D03*
X1352803Y952194D03*
X1356678Y959694D03*
X1348928D03*
X1453451Y499121D03*
X1472480Y499018D03*
X1457326Y506621D03*
X1449576D03*
X1468605Y506518D03*
X1462823Y952111D03*
X1466698Y959611D03*
X1458948D03*
X1473140Y959652D03*
X1476355Y506518D03*
X1477015Y952152D03*
X1480890Y959652D03*
X1586992Y499356D03*
X1601101Y499355D03*
X1590867Y506856D03*
X1583117D03*
X1604976Y506855D03*
X1597226D03*
X1587036Y952237D03*
X1590911Y959737D03*
X1583161D03*
X1601228Y952278D03*
X1605103Y959778D03*
X1597353D03*
X1711457Y499103D03*
X1715332Y506603D03*
X1707582D03*
X1725566Y499102D03*
X1729441Y506602D03*
X1721691D03*
X1749573Y952193D03*
X1753448Y959693D03*
X1745698D03*
X1763765Y952234D03*
X1759890Y959734D03*
X1792236Y951851D03*
X1796111Y959351D03*
X1788361D03*
X1806452Y952110D03*
X1810327Y959610D03*
X1802577D03*
X1767640Y959734D03*
X1835292Y499230D03*
X1849401Y499229D03*
X1839167Y506730D03*
X1831417D03*
X1853276Y506729D03*
X1845526D03*
G54D81*
X683341Y593826D03*
X689747D03*
G54D72*
X580829Y549721D03*
Y535941D03*
X560729D03*
Y549721D03*
X929950Y1522310D03*
Y1536090D03*
X950050D03*
Y1522310D03*
X1447150Y542710D03*
X1467250D03*
X1447150Y556490D03*
X1467250D03*
G54D45*
X77877Y194861D03*
X80437D03*
X82997D03*
X77877Y187461D03*
X80437D03*
X82997D03*
Y647617D03*
X80437D03*
X77877D03*
Y640217D03*
X80437D03*
X82997D03*
Y1100373D03*
X80437D03*
X77877D03*
Y1092973D03*
X80437D03*
X82997D03*
X202089Y194861D03*
X204649D03*
X207209D03*
X202089Y187461D03*
X204649D03*
X207209D03*
X207409Y638617D03*
X204849D03*
X202289D03*
Y631217D03*
X204849D03*
X207409D03*
X207209Y1100373D03*
X204649D03*
X202089D03*
Y1092973D03*
X204649D03*
X207209D03*
X326302Y194861D03*
X328862D03*
X331422D03*
X326302Y187461D03*
X328862D03*
X331422D03*
Y647617D03*
X328862D03*
X326302D03*
Y640217D03*
X328862D03*
X331422D03*
Y1100373D03*
X328862D03*
X326302D03*
Y1092973D03*
X328862D03*
X331422D03*
X450514Y194861D03*
X453074D03*
X455634D03*
X450514Y187461D03*
X453074D03*
X455634D03*
Y647617D03*
X453074D03*
X450514D03*
Y640217D03*
X453074D03*
X455634D03*
X574727Y194861D03*
X577287D03*
X579847D03*
X574727Y187461D03*
X577287D03*
X579847D03*
Y647617D03*
X577287D03*
X574727D03*
Y640217D03*
X577287D03*
X579847D03*
Y1100373D03*
X577287D03*
X574727D03*
Y1092973D03*
X577287D03*
X579847D03*
X698940Y194861D03*
X701500D03*
X698940Y187461D03*
X701500D03*
X699140Y649117D03*
Y641717D03*
X701500Y1100373D03*
X698940D03*
Y1092973D03*
X701500D03*
X704060Y194861D03*
Y187461D03*
X704260Y649117D03*
X701700D03*
Y641717D03*
X704260D03*
X704060Y1100373D03*
Y1092973D03*
X1021660Y-56732D03*
X1019100D03*
X1016540D03*
X1021660Y-49332D03*
X1019100D03*
X1016540D03*
X1006660Y-59968D03*
X1004100D03*
X1001540D03*
X1006660Y-52568D03*
X1004100D03*
X1001540D03*
X1086740Y-77432D03*
X1076960Y-63832D03*
X1074400D03*
X1071840D03*
X1076960Y-56432D03*
X1074400D03*
X1071840D03*
X1086740Y-70032D03*
X1091860Y-77432D03*
X1089300D03*
X1109922Y-72521D03*
X1107362D03*
X1104802D03*
X1109922Y-65121D03*
X1107362D03*
X1104802D03*
X1091860Y-70032D03*
X1089300D03*
G54D27*
X66437Y188161D03*
Y179161D03*
Y631917D03*
Y640917D03*
Y1084673D03*
Y1093673D03*
X190649Y188161D03*
Y179161D03*
X194749Y621417D03*
Y630417D03*
X190651Y1086035D03*
Y1095035D03*
X314862Y188161D03*
Y179161D03*
Y631917D03*
Y640917D03*
Y1084673D03*
Y1093673D03*
X439074Y188161D03*
Y179161D03*
Y631917D03*
Y640917D03*
X513517Y576931D03*
Y567931D03*
X563287Y188161D03*
Y179161D03*
Y631917D03*
Y640917D03*
Y1084673D03*
Y1093673D03*
X687500Y188161D03*
Y179161D03*
X691600Y631917D03*
Y640917D03*
X687500Y1084673D03*
Y1093673D03*
X882500Y1522868D03*
Y1531868D03*
X1087700Y-51200D03*
Y-42200D03*
X1514297Y544511D03*
Y553511D03*
G54D54*
X145237Y256161D03*
Y708917D03*
Y1161673D03*
X269449Y256161D03*
Y708917D03*
Y1161673D03*
X393662Y256161D03*
Y708917D03*
X393462Y1161673D03*
X505674Y1130873D03*
X517874Y256161D03*
Y708917D03*
X531474Y1152773D03*
X642087Y256161D03*
Y708917D03*
Y1161673D03*
X833108Y37372D03*
X868377Y37234D03*
X937809Y991763D03*
X914882Y1534500D03*
X1113100Y-48400D03*
X1435000Y544600D03*
X1460061Y588256D03*
X1503682Y539100D03*
X1887132Y1054227D03*
G54D63*
X429724Y68307D03*
X458071D03*
X443898D03*
X429724Y87993D03*
Y82481D03*
Y73819D03*
X458071Y87993D03*
Y82481D03*
X450984Y91930D03*
Y86418D03*
X443898Y87993D03*
Y82481D03*
X436811Y91930D03*
Y86418D03*
X458071Y73819D03*
X450984Y77756D03*
Y72245D03*
X443898Y73819D03*
X436811Y77756D03*
Y72245D03*
X472244Y68307D03*
X479331Y91930D03*
Y86418D03*
X472244Y87993D03*
Y82481D03*
X465157Y91930D03*
Y86418D03*
X479331Y77756D03*
Y72245D03*
X472244Y73819D03*
X465157Y77756D03*
Y72245D03*
X514764Y68307D03*
X543110D03*
X528937D03*
X557283D03*
X514764Y87993D03*
Y82481D03*
Y73819D03*
X550197Y91930D03*
Y86418D03*
X543110Y87993D03*
Y82481D03*
X536024Y91930D03*
Y86418D03*
X528937Y87993D03*
Y82481D03*
X521850Y91930D03*
Y86418D03*
X550197Y77756D03*
Y72245D03*
X543110Y73819D03*
X536024Y77756D03*
Y72245D03*
X528937Y73819D03*
X521850Y77756D03*
Y72245D03*
X557283Y87993D03*
Y82481D03*
Y73819D03*
X564370Y91930D03*
Y86418D03*
Y77756D03*
Y72245D03*
X1398228Y68307D03*
X1426575D03*
X1412402D03*
X1398228Y87993D03*
Y82481D03*
Y73819D03*
X1426575Y87993D03*
Y82481D03*
X1419488Y91930D03*
Y86418D03*
X1412402Y87993D03*
Y82481D03*
X1405315Y91930D03*
Y86418D03*
X1426575Y73819D03*
X1419488Y77756D03*
Y72245D03*
X1412402Y73819D03*
X1405315Y77756D03*
Y72245D03*
X1440748Y68307D03*
X1447835Y91930D03*
Y86418D03*
X1440748Y87993D03*
Y82481D03*
X1433661Y91930D03*
Y86418D03*
X1447835Y77756D03*
Y72245D03*
X1440748Y73819D03*
X1433661Y77756D03*
Y72245D03*
X1483268Y68307D03*
X1511614D03*
X1497441D03*
X1483268Y87993D03*
Y82481D03*
Y73819D03*
X1518701Y91930D03*
Y86418D03*
X1511614Y87993D03*
Y82481D03*
X1504528Y91930D03*
Y86418D03*
X1497441Y87993D03*
Y82481D03*
X1490354Y91930D03*
Y86418D03*
X1518701Y77756D03*
Y72245D03*
X1511614Y73819D03*
X1504528Y77756D03*
Y72245D03*
X1497441Y73819D03*
X1490354Y77756D03*
Y72245D03*
X1525787Y68307D03*
X1532874Y91930D03*
Y86418D03*
X1525787Y87993D03*
Y82481D03*
X1532874Y77756D03*
Y72245D03*
X1525787Y73819D03*
G54D18*
X60540Y-85109D03*
X59536Y1573374D03*
X79000Y1301900D03*
X1826700Y77600D03*
X1865705Y1573374D03*
X1898432Y-93682D03*
X1908500Y1346800D03*
G54D28*
X64437Y209361D03*
Y662017D03*
Y1114773D03*
X138428Y966735D03*
X188649Y209061D03*
X205128Y554735D03*
X188349Y1110473D03*
X312862Y209161D03*
Y661917D03*
Y1114773D03*
X437074Y209161D03*
X437174Y661917D03*
X504674Y1114573D03*
X561387Y209161D03*
Y661917D03*
X561287Y1114673D03*
X685500Y209261D03*
Y662017D03*
X685200Y1110373D03*
X870963Y818831D03*
X869863Y1487165D03*
X1032430Y834829D03*
X1009900Y939000D03*
X1182540Y257688D03*
X1177965Y281343D03*
X1228892Y225125D03*
X1253200Y240661D03*
X1251200Y693417D03*
Y1146173D03*
X1377413Y240661D03*
X1375413Y693417D03*
Y1146173D03*
X1499725Y240561D03*
X1499625Y693417D03*
Y1146173D03*
X1625438Y240561D03*
X1623838Y693417D03*
X1635638Y1146173D03*
X1750250Y240561D03*
X1748050Y1146173D03*
X1780228Y978735D03*
X1856169Y209161D03*
Y661917D03*
X1856391Y1102987D03*
G54D82*
X794488Y11615D03*
X885040D03*
G54D46*
X93437Y239661D03*
Y250661D03*
Y692417D03*
Y703417D03*
Y1156173D03*
Y1145173D03*
X217649Y239661D03*
Y250661D03*
Y692417D03*
Y703417D03*
Y1156173D03*
Y1145173D03*
X341862Y239661D03*
Y250661D03*
Y692417D03*
Y703417D03*
Y1156173D03*
Y1145173D03*
X466074Y239661D03*
Y250661D03*
Y692417D03*
Y703417D03*
X515774Y1156173D03*
Y1145173D03*
X590287Y239661D03*
Y250661D03*
Y692417D03*
Y703417D03*
Y1156173D03*
Y1145173D03*
X714500Y239661D03*
Y250661D03*
Y692417D03*
Y703417D03*
Y1156173D03*
Y1145173D03*
X1308500Y253661D03*
Y264661D03*
Y717417D03*
Y706417D03*
Y1170173D03*
Y1159173D03*
X1432713Y253661D03*
Y264661D03*
Y717417D03*
Y706417D03*
Y1170173D03*
Y1159173D03*
X1556925Y253661D03*
Y264661D03*
Y717417D03*
Y706417D03*
Y1170173D03*
Y1159173D03*
X1681138Y253661D03*
Y264661D03*
Y717417D03*
Y706417D03*
Y1170173D03*
Y1159173D03*
X1805350Y253661D03*
Y264661D03*
Y717417D03*
Y706417D03*
Y1170173D03*
Y1159173D03*
X1885169Y250661D03*
Y239661D03*
Y692417D03*
Y703417D03*
X1885553Y1131673D03*
Y1142673D03*
G54D64*
X460873Y1081266D03*
X453473D03*
X460873Y1083826D03*
Y1086386D03*
X453473D03*
Y1083826D03*
X1303800Y180721D03*
Y178161D03*
Y175601D03*
X1311200D03*
Y178161D03*
Y180721D03*
X1303800Y633477D03*
Y630917D03*
Y628357D03*
X1311200D03*
Y630917D03*
Y633477D03*
X1303800Y1081113D03*
X1311200D03*
X1303800Y1086233D03*
Y1083673D03*
X1311200D03*
Y1086233D03*
X1428013Y180721D03*
Y178161D03*
Y175601D03*
Y633477D03*
Y630917D03*
Y628357D03*
Y1081113D03*
Y1086233D03*
Y1083673D03*
X1435413Y175601D03*
Y178161D03*
Y180721D03*
Y628357D03*
Y630917D03*
Y633477D03*
Y1081113D03*
Y1083673D03*
Y1086233D03*
X1552225Y180721D03*
Y178161D03*
Y175601D03*
X1559625D03*
Y178161D03*
Y180721D03*
X1552225Y633477D03*
Y630917D03*
Y628357D03*
X1559625D03*
Y630917D03*
Y633477D03*
X1552225Y1081113D03*
X1559625D03*
X1552225Y1086233D03*
Y1083673D03*
X1559625D03*
Y1086233D03*
X1676438Y180721D03*
Y178161D03*
Y175601D03*
X1683838D03*
Y178161D03*
Y180721D03*
X1676438Y633477D03*
Y630917D03*
Y628357D03*
X1683838D03*
Y630917D03*
Y633477D03*
X1676438Y1081113D03*
X1683838D03*
X1676438Y1086233D03*
Y1083673D03*
X1683838D03*
Y1086233D03*
X1800650Y180721D03*
Y178161D03*
Y175601D03*
X1808050D03*
Y178161D03*
Y180721D03*
X1800650Y633477D03*
Y630917D03*
Y628357D03*
X1808050D03*
Y630917D03*
Y633477D03*
X1800650Y1081113D03*
X1808050D03*
X1800650Y1086233D03*
Y1083673D03*
X1808050D03*
Y1086233D03*
X1859117Y171015D03*
Y173575D03*
Y176135D03*
X1851717D03*
Y173575D03*
Y171015D03*
X1859117Y623771D03*
Y626331D03*
Y628891D03*
X1851717D03*
Y626331D03*
Y623771D03*
X1871030Y1076940D03*
Y1079500D03*
Y1082060D03*
X1863630D03*
Y1079500D03*
Y1076940D03*
G54D73*
X580529Y547752D03*
Y545784D03*
Y543815D03*
Y541847D03*
Y539878D03*
Y537910D03*
X561029D03*
Y539878D03*
Y541847D03*
Y543815D03*
Y545784D03*
Y547752D03*
X930250Y1524279D03*
Y1526247D03*
Y1528216D03*
Y1530184D03*
Y1532153D03*
Y1534121D03*
X949750D03*
Y1532153D03*
Y1530184D03*
Y1528216D03*
Y1526247D03*
Y1524279D03*
X1447450Y544679D03*
Y546647D03*
Y548616D03*
Y550584D03*
X1466950D03*
Y548616D03*
Y546647D03*
Y544679D03*
X1447450Y552553D03*
Y554521D03*
X1466950D03*
Y552553D03*
G54D37*
X72500Y498200D03*
X67500D03*
X72500Y950955D03*
X67500D03*
X126063Y974025D03*
X196712Y498200D03*
X191712D03*
X192763Y562025D03*
X216712Y950755D03*
X221712D03*
X313312Y103231D03*
X320925Y498200D03*
X315925D03*
X320925Y950955D03*
X315925D03*
X445138Y498200D03*
X440138D03*
X445138Y950955D03*
X440138D03*
X539350Y498200D03*
X534350D03*
X520479Y558913D03*
X569350Y950955D03*
X564350D03*
X652663Y506200D03*
X647663D03*
X607460Y550474D03*
X693563Y950955D03*
X688563D03*
X749000Y666200D03*
X865663Y838753D03*
X892700Y1534118D03*
X939000Y1007400D03*
X944776Y935200D03*
X987970Y1008207D03*
X967813Y1543366D03*
X1027063Y855053D03*
X1017000Y1099200D03*
X1064500Y1100200D03*
X1094200Y-48400D03*
X1107100Y1100100D03*
X1269878Y498621D03*
X1264878D03*
X1268742Y950786D03*
X1263742D03*
X1312999Y111325D03*
X1364882Y498200D03*
X1359882D03*
X1367382Y950955D03*
X1362382D03*
X1426419Y516457D03*
X1443700Y519800D03*
X1491594Y498200D03*
X1486594D03*
X1491594Y950955D03*
X1486594D03*
X1615807Y498200D03*
X1610807D03*
X1615807Y950955D03*
X1610807D03*
X1740019Y498200D03*
X1735019D03*
X1740019Y950955D03*
X1735019D03*
X1767863Y986025D03*
X1782666Y950944D03*
X1777666D03*
X1859232Y498200D03*
X1869500Y184944D03*
X1864232Y498200D03*
X1869500Y637700D03*
G54D19*
X59937Y187361D03*
Y640117D03*
Y1092873D03*
X108363Y998925D03*
X112500Y998980D03*
X184149Y187461D03*
X175063Y586925D03*
X179200Y586980D03*
X188649Y629617D03*
X306955Y71879D03*
X314370Y125341D03*
X308362Y187461D03*
X308262Y640217D03*
Y1092973D03*
X323813Y125322D03*
X328321Y125299D03*
X318909Y125343D03*
X333021Y125355D03*
X365162Y84670D03*
X432574Y187461D03*
Y640117D03*
X447173Y1075426D03*
X442473D03*
X556787Y187361D03*
X549279Y520031D03*
X553279D03*
X556787Y640117D03*
Y1092973D03*
X580279Y520031D03*
X557279Y567031D03*
X592779Y574031D03*
X579718Y574097D03*
X571540Y574065D03*
X615100Y520300D03*
X611910Y565974D03*
X637213Y589355D03*
X681000Y187361D03*
X685500Y640117D03*
X680400Y1101000D03*
X878673Y811303D03*
X883400Y811332D03*
X881448Y1358507D03*
X881420Y1350388D03*
X882000Y1439200D03*
X873000D03*
X893050Y1486000D03*
X879321Y1485961D03*
X883947Y1485970D03*
X860000Y1504700D03*
X850500D03*
X914600Y912400D03*
X927861Y962907D03*
X921600Y981900D03*
X916500Y962800D03*
X925053Y1032085D03*
X916769Y1032139D03*
X936959Y1366990D03*
X936964Y1353312D03*
X932294Y1376548D03*
X922500Y1506400D03*
X918500D03*
X941000Y1560400D03*
X926500Y1553400D03*
X957000Y911700D03*
X970500D03*
X952500D03*
X954900Y957100D03*
X950400D03*
X959400D03*
X955000Y982700D03*
X964000D03*
X945790Y953862D03*
X955700Y1027500D03*
X951200D03*
X946700D03*
X947159Y1365287D03*
X951525Y1376357D03*
X950300Y1506400D03*
X988573Y1509912D03*
X962000Y1560400D03*
X949000D03*
X972413Y1556866D03*
X1038712Y-38558D03*
X1004100Y-70032D03*
X1035973Y830903D03*
X1034400Y908400D03*
X1002194Y981540D03*
X1006694D03*
X1007849Y1030543D03*
X1003194Y1030540D03*
X993649Y1030543D03*
X1012494Y1030640D03*
X998439Y1030537D03*
X1028000Y1073700D03*
X1022400Y1121500D03*
X1031400D03*
X1026900D03*
X1017800Y1144200D03*
X1008700D03*
X995000D03*
X1009500Y1187700D03*
X1014500D03*
X1004500D03*
X1061325Y-44000D03*
X1074400Y-42332D03*
X1040773Y830903D03*
X1054419Y835653D03*
X1048400Y908400D03*
X1057700D03*
X1064918Y942349D03*
X1069918D03*
X1087000Y1073700D03*
X1078000D03*
X1041500D03*
X1087700Y1122600D03*
X1074500Y1122700D03*
X1079000D03*
X1070155Y1122703D03*
X1083355D03*
X1115200Y1073800D03*
X1128900D03*
X1119500Y1121900D03*
X1124100D03*
X1115000D03*
X1176100Y266200D03*
X1176835Y614632D03*
X1192300Y268568D03*
X1194600Y296100D03*
X1197100Y275900D03*
X1250410Y236409D03*
X1327921Y86155D03*
X1299569Y90891D03*
X1315115Y133800D03*
X1324207Y133803D03*
X1319797Y133788D03*
X1328534D03*
X1312000Y169361D03*
X1322000D03*
X1326400Y181761D03*
X1321900D03*
X1312000Y622117D03*
X1322000D03*
X1326500Y634517D03*
X1322000D03*
X1309600Y1074873D03*
X1317400Y1074900D03*
X1326500Y1087273D03*
X1322000D03*
X1332934Y133788D03*
X1421969Y531357D03*
X1436213Y169361D03*
X1446213D03*
X1450713Y181761D03*
X1446013D03*
X1463085Y506585D03*
X1452200Y575800D03*
X1470700D03*
X1437200Y566300D03*
X1436213Y622117D03*
X1446213D03*
X1450713Y634517D03*
X1446013D03*
X1436213Y1074873D03*
X1446213D03*
X1450713Y1087273D03*
X1446013D03*
X1502400Y550850D03*
X1481938Y506470D03*
X1560425Y169361D03*
X1570425D03*
X1570125Y181761D03*
X1560425Y622117D03*
X1570425D03*
X1570225Y634517D03*
X1560425Y1074873D03*
X1570425D03*
Y1087373D03*
X1574925Y181761D03*
Y634517D03*
Y1087373D03*
X1684638Y169361D03*
X1694638D03*
X1699138Y181761D03*
X1694438D03*
X1684638Y622117D03*
X1694638D03*
X1699138Y634517D03*
X1694438D03*
X1684638Y1074873D03*
X1694638D03*
X1699138Y1087273D03*
X1694438D03*
X1750163Y1010925D03*
X1754300Y1010980D03*
X1808850Y169361D03*
Y622117D03*
X1805250Y1074673D03*
X1818850Y169361D03*
X1823350Y181761D03*
X1818650D03*
X1845517Y165175D03*
X1841017D03*
X1818850Y622117D03*
X1823350Y634517D03*
X1818650D03*
X1845417Y617931D03*
X1840917D03*
X1815250Y1074673D03*
X1823350Y1087273D03*
X1818650D03*
X1838074Y1092395D03*
X1836200Y1136620D03*
X1878900Y190944D03*
Y643700D03*
X1876662Y1062126D03*
X1872162D03*
G54D91*
X929331Y16536D03*
X937205Y20473D03*
Y12599D03*
X929331Y63780D03*
X937205Y67717D03*
X929331Y48032D03*
Y40158D03*
Y32284D03*
Y24410D03*
X937205Y51969D03*
Y44095D03*
Y36221D03*
Y28347D03*
X929331Y111024D03*
Y103150D03*
Y95276D03*
Y87402D03*
Y79528D03*
Y71654D03*
X937205Y114961D03*
Y107087D03*
Y99213D03*
Y91339D03*
Y83465D03*
Y75591D03*
X929331Y166142D03*
Y158268D03*
Y150394D03*
Y142520D03*
Y134646D03*
Y126772D03*
Y118898D03*
X937205Y162205D03*
Y154331D03*
Y146457D03*
Y138583D03*
Y130709D03*
Y122835D03*
X929331Y213386D03*
Y205512D03*
Y197638D03*
Y189764D03*
Y181890D03*
Y174016D03*
X937205Y209449D03*
Y201575D03*
Y193701D03*
Y185827D03*
Y177953D03*
Y170079D03*
X929331Y260630D03*
Y252756D03*
Y244882D03*
Y237008D03*
Y229134D03*
Y221260D03*
X937205Y256693D03*
Y248819D03*
Y240945D03*
Y233071D03*
Y225197D03*
Y217323D03*
X929331Y307874D03*
Y300000D03*
Y292126D03*
Y284252D03*
Y276378D03*
Y268504D03*
X937205Y303937D03*
Y296063D03*
Y288189D03*
Y280315D03*
Y272441D03*
Y264567D03*
X929331Y339371D03*
Y331496D03*
Y323622D03*
Y315748D03*
X937205Y335434D03*
Y327559D03*
Y319685D03*
Y311811D03*
X929331Y403543D03*
Y395669D03*
X937205Y407480D03*
Y399606D03*
Y391732D03*
X929331Y450787D03*
Y442913D03*
X937205Y454724D03*
Y446850D03*
X929331Y427165D03*
Y419291D03*
Y411417D03*
X937205Y431102D03*
Y423228D03*
Y415354D03*
X929331Y498031D03*
Y490157D03*
Y482283D03*
Y474409D03*
Y466535D03*
Y458661D03*
X937205Y501968D03*
Y494094D03*
Y486220D03*
Y478346D03*
Y470472D03*
Y462598D03*
X929331Y553149D03*
Y545275D03*
Y537401D03*
Y529527D03*
Y521653D03*
Y513779D03*
Y505905D03*
X937205Y549212D03*
Y541338D03*
Y533464D03*
Y525590D03*
Y517716D03*
Y509842D03*
X929331Y600393D03*
Y592519D03*
Y584645D03*
Y576771D03*
Y568897D03*
Y561023D03*
X937205Y596456D03*
Y588582D03*
Y580708D03*
Y572834D03*
Y564960D03*
Y557086D03*
X929331Y647637D03*
Y639763D03*
Y631889D03*
Y624015D03*
Y616141D03*
Y608267D03*
X937205Y643700D03*
Y635826D03*
Y627952D03*
Y620078D03*
Y612204D03*
Y604330D03*
X929331Y694881D03*
Y687007D03*
Y679133D03*
Y671259D03*
Y663385D03*
Y655511D03*
X937205Y690944D03*
Y683070D03*
Y675196D03*
Y667322D03*
Y659448D03*
Y651574D03*
X929331Y718504D03*
Y710629D03*
Y702755D03*
X937205Y714567D03*
Y706692D03*
Y698818D03*
X954921Y16536D03*
X947047Y20473D03*
Y12599D03*
X954921Y63780D03*
X947047Y67717D03*
X954921Y48032D03*
Y40158D03*
Y32284D03*
Y24410D03*
X947047Y51969D03*
Y44095D03*
Y36221D03*
Y28347D03*
X954921Y111024D03*
Y103150D03*
Y95276D03*
Y87402D03*
Y79528D03*
Y71654D03*
X947047Y114961D03*
Y107087D03*
Y99213D03*
Y91339D03*
Y83465D03*
Y75591D03*
X954921Y166142D03*
Y158268D03*
Y150394D03*
Y142520D03*
Y134646D03*
Y126772D03*
Y118898D03*
X947047Y162205D03*
Y154331D03*
Y146457D03*
Y138583D03*
Y130709D03*
Y122835D03*
X954921Y213386D03*
Y205512D03*
Y197638D03*
Y189764D03*
Y181890D03*
Y174016D03*
X947047Y209449D03*
Y201575D03*
Y193701D03*
Y185827D03*
Y177953D03*
Y170079D03*
X954921Y260630D03*
Y252756D03*
Y244882D03*
Y237008D03*
Y229134D03*
Y221260D03*
X947047Y256693D03*
Y248819D03*
Y240945D03*
Y233071D03*
Y225197D03*
Y217323D03*
X954921Y307874D03*
Y300000D03*
Y292126D03*
Y284252D03*
Y276378D03*
Y268504D03*
X947047Y303937D03*
Y296063D03*
Y288189D03*
Y280315D03*
Y272441D03*
Y264567D03*
X954921Y339371D03*
Y331496D03*
Y323622D03*
Y315748D03*
X947047Y335434D03*
Y327559D03*
Y319685D03*
Y311811D03*
X954921Y403543D03*
Y395669D03*
X947047Y407480D03*
Y399606D03*
Y391732D03*
X954921Y450787D03*
Y442913D03*
X947047Y454724D03*
Y446850D03*
X954921Y427165D03*
Y419291D03*
Y411417D03*
X947047Y431102D03*
Y423228D03*
Y415354D03*
X954921Y498031D03*
Y490157D03*
Y482283D03*
Y474409D03*
Y466535D03*
Y458661D03*
X947047Y501968D03*
Y494094D03*
Y486220D03*
Y478346D03*
Y470472D03*
Y462598D03*
X954921Y553149D03*
Y545275D03*
Y537401D03*
Y529527D03*
Y521653D03*
Y513779D03*
Y505905D03*
X947047Y549212D03*
Y541338D03*
Y533464D03*
Y525590D03*
Y517716D03*
Y509842D03*
X954921Y600393D03*
Y592519D03*
Y584645D03*
Y576771D03*
Y568897D03*
Y561023D03*
X947047Y596456D03*
Y588582D03*
Y580708D03*
Y572834D03*
Y564960D03*
Y557086D03*
X954921Y647637D03*
Y639763D03*
Y631889D03*
Y624015D03*
Y616141D03*
Y608267D03*
X947047Y643700D03*
Y635826D03*
Y627952D03*
Y620078D03*
Y612204D03*
Y604330D03*
X954921Y694881D03*
Y687007D03*
Y679133D03*
Y671259D03*
Y663385D03*
Y655511D03*
X947047Y690944D03*
Y683070D03*
Y675196D03*
Y667322D03*
Y659448D03*
Y651574D03*
X954921Y718504D03*
Y710629D03*
Y702755D03*
X947047Y714567D03*
Y706692D03*
Y698818D03*
X1123031Y16536D03*
X1097441D03*
X1115157Y20473D03*
Y12599D03*
X1105315Y20473D03*
Y12599D03*
X1123031Y63780D03*
X1097441D03*
X1115157Y67717D03*
X1105315D03*
X1123031Y48032D03*
Y40158D03*
Y32284D03*
Y24410D03*
X1097441Y48032D03*
Y40158D03*
Y32284D03*
Y24410D03*
X1115157Y51969D03*
Y44095D03*
Y36221D03*
Y28347D03*
X1105315Y51969D03*
Y44095D03*
Y36221D03*
Y28347D03*
X1123031Y111024D03*
Y103150D03*
Y95276D03*
Y87402D03*
Y79528D03*
Y71654D03*
X1097441Y111024D03*
Y103150D03*
Y95276D03*
Y87402D03*
Y79528D03*
Y71654D03*
X1115157Y114961D03*
Y107087D03*
Y99213D03*
Y91339D03*
Y83465D03*
Y75591D03*
X1105315Y114961D03*
Y107087D03*
Y99213D03*
Y91339D03*
Y83465D03*
Y75591D03*
X1123031Y166142D03*
Y158268D03*
Y150394D03*
Y142520D03*
Y134646D03*
Y126772D03*
Y118898D03*
X1097441Y166142D03*
Y158268D03*
Y150394D03*
Y142520D03*
Y134646D03*
Y126772D03*
Y118898D03*
X1115157Y162205D03*
Y154331D03*
Y146457D03*
Y138583D03*
Y130709D03*
Y122835D03*
X1105315Y162205D03*
Y154331D03*
Y146457D03*
Y138583D03*
Y130709D03*
Y122835D03*
X1123031Y213386D03*
Y205512D03*
Y197638D03*
Y189764D03*
Y181890D03*
Y174016D03*
X1097441Y213386D03*
Y205512D03*
Y197638D03*
Y189764D03*
Y181890D03*
Y174016D03*
X1115157Y209449D03*
Y201575D03*
Y193701D03*
Y185827D03*
Y177953D03*
Y170079D03*
X1105315Y209449D03*
Y201575D03*
Y193701D03*
Y185827D03*
Y177953D03*
Y170079D03*
X1123031Y260630D03*
Y252756D03*
Y244882D03*
Y237008D03*
Y229134D03*
Y221260D03*
X1097441Y260630D03*
Y252756D03*
Y244882D03*
Y237008D03*
Y229134D03*
Y221260D03*
X1115157Y256693D03*
Y248819D03*
Y240945D03*
Y233071D03*
Y225197D03*
Y217323D03*
X1105315Y256693D03*
Y248819D03*
Y240945D03*
Y233071D03*
Y225197D03*
Y217323D03*
X1123031Y307874D03*
Y300000D03*
Y292126D03*
Y284252D03*
Y276378D03*
Y268504D03*
X1097441Y307874D03*
Y300000D03*
Y292126D03*
Y284252D03*
Y276378D03*
Y268504D03*
X1115157Y303937D03*
Y296063D03*
Y288189D03*
Y280315D03*
Y272441D03*
Y264567D03*
X1105315Y303937D03*
Y296063D03*
Y288189D03*
Y280315D03*
Y272441D03*
Y264567D03*
X1123031Y339371D03*
Y331496D03*
Y323622D03*
Y315748D03*
X1097441Y339371D03*
Y331496D03*
Y323622D03*
Y315748D03*
X1115157Y335434D03*
Y327559D03*
Y319685D03*
Y311811D03*
X1105315Y335434D03*
Y327559D03*
Y319685D03*
Y311811D03*
X1123031Y403543D03*
Y395669D03*
X1097441Y403543D03*
Y395669D03*
X1115157Y407480D03*
Y399606D03*
Y391732D03*
X1105315Y407480D03*
Y399606D03*
Y391732D03*
X1123031Y450787D03*
Y442913D03*
X1097441Y450787D03*
Y442913D03*
X1115157Y454724D03*
Y446850D03*
X1105315Y454724D03*
Y446850D03*
X1123031Y427165D03*
Y419291D03*
Y411417D03*
X1097441Y427165D03*
Y419291D03*
Y411417D03*
X1115157Y431102D03*
Y423228D03*
Y415354D03*
X1105315Y431102D03*
Y423228D03*
Y415354D03*
X1123031Y498031D03*
Y490157D03*
Y482283D03*
Y474409D03*
Y466535D03*
Y458661D03*
X1097441Y498031D03*
Y490157D03*
Y482283D03*
Y474409D03*
Y466535D03*
Y458661D03*
X1115157Y501968D03*
Y494094D03*
Y486220D03*
Y478346D03*
Y470472D03*
Y462598D03*
X1105315Y501968D03*
Y494094D03*
Y486220D03*
Y478346D03*
Y470472D03*
Y462598D03*
X1123031Y553149D03*
Y545275D03*
Y537401D03*
Y529527D03*
Y521653D03*
Y513779D03*
Y505905D03*
X1097441Y553149D03*
Y545275D03*
Y537401D03*
Y529527D03*
Y521653D03*
Y513779D03*
Y505905D03*
X1115157Y549212D03*
Y541338D03*
Y533464D03*
Y525590D03*
Y517716D03*
Y509842D03*
X1105315Y549212D03*
Y541338D03*
Y533464D03*
Y525590D03*
Y517716D03*
Y509842D03*
X1123031Y600393D03*
Y592519D03*
Y584645D03*
Y576771D03*
Y568897D03*
Y561023D03*
X1097441Y600393D03*
Y592519D03*
Y584645D03*
Y576771D03*
Y568897D03*
Y561023D03*
X1115157Y596456D03*
Y588582D03*
Y580708D03*
Y572834D03*
Y564960D03*
Y557086D03*
X1105315Y596456D03*
Y588582D03*
Y580708D03*
Y572834D03*
Y564960D03*
Y557086D03*
X1123031Y647637D03*
Y639763D03*
Y631889D03*
Y624015D03*
Y616141D03*
Y608267D03*
X1097441Y647637D03*
Y639763D03*
Y631889D03*
Y624015D03*
Y616141D03*
Y608267D03*
X1115157Y643700D03*
Y635826D03*
Y627952D03*
Y620078D03*
Y612204D03*
Y604330D03*
X1105315Y643700D03*
Y635826D03*
Y627952D03*
Y620078D03*
Y612204D03*
Y604330D03*
X1123031Y694881D03*
Y687007D03*
Y679133D03*
Y671259D03*
Y663385D03*
Y655511D03*
X1097441Y694881D03*
Y687007D03*
Y679133D03*
Y671259D03*
Y663385D03*
Y655511D03*
X1115157Y690944D03*
Y683070D03*
Y675196D03*
Y667322D03*
Y659448D03*
Y651574D03*
X1105315Y690944D03*
Y683070D03*
Y675196D03*
Y667322D03*
Y659448D03*
Y651574D03*
X1123031Y718504D03*
Y710629D03*
Y702755D03*
X1097441Y718504D03*
Y710629D03*
Y702755D03*
X1115157Y714567D03*
Y706692D03*
Y698818D03*
X1105315Y714567D03*
Y706692D03*
Y698818D03*
G54D55*
X139937Y270661D03*
Y723417D03*
X147063Y1005225D03*
X140100Y1176000D03*
X213763Y593225D03*
X264149Y270661D03*
Y723417D03*
X264200Y1176000D03*
X388362Y270661D03*
Y723417D03*
X388200Y1176000D03*
X512574Y270661D03*
Y723417D03*
X512500Y1176000D03*
X636787Y270461D03*
Y723417D03*
X636800Y1176000D03*
X749000Y723417D03*
X751300Y270500D03*
X760900Y1176000D03*
X884000Y503300D03*
X884069Y536587D03*
X884143Y522805D03*
Y516205D03*
X884069Y529987D03*
X883969Y548187D03*
X884143Y509905D03*
X884069Y587087D03*
X884143Y593105D03*
Y599205D03*
X884043Y605505D03*
Y611905D03*
X869534Y1363511D03*
X988795Y1571058D03*
Y1576658D03*
X1005471Y14243D03*
X1005571Y7943D03*
Y20443D03*
X1005471Y26543D03*
Y32343D03*
X1005371Y44043D03*
X1005457Y38271D03*
X1005557Y49871D03*
X1005898Y72514D03*
Y79114D03*
X1005157Y579054D03*
X1026106Y1545595D03*
Y1539995D03*
X1031706Y1545595D03*
Y1539995D03*
X1020574Y1540059D03*
Y1545659D03*
X1039758Y1559605D03*
X1014974Y1540059D03*
Y1545659D03*
X1039358Y1565405D03*
X1033717Y1563634D03*
X1028223Y1563763D03*
X1022623D03*
X994305Y1566342D03*
X1017023Y1563763D03*
X1011476Y1565175D03*
X1005658Y1565005D03*
X1000058D03*
X1039958Y1553705D03*
Y1548105D03*
Y1542505D03*
X1039358Y1571005D03*
Y1576605D03*
X1005658Y1575905D03*
X1033917Y1574834D03*
X1033717Y1569234D03*
X1000058Y1575905D03*
X1028423Y1574963D03*
X1028223Y1569363D03*
X994460Y1577240D03*
X1022823Y1574963D03*
X1022623Y1569363D03*
X1017223Y1574963D03*
X1017023Y1569363D03*
X994305Y1571942D03*
X1011676Y1576375D03*
X1011476Y1570775D03*
X1005658Y1570605D03*
X1000058D03*
X1072205Y31082D03*
Y38982D03*
X1067705Y35182D03*
X1067805Y27282D03*
X1067705Y42682D03*
X1072382Y46195D03*
X1067200Y48900D03*
X1072200Y52000D03*
X1072132Y64668D03*
Y70368D03*
X1051915Y518253D03*
Y524853D03*
X1051869Y538079D03*
Y531479D03*
X1051957Y505702D03*
Y512302D03*
X1051131Y586321D03*
X1051185Y574247D03*
X1051147Y598615D03*
Y592415D03*
X1051185Y580347D03*
X1051200Y568300D03*
X1051181Y562366D03*
X1078358Y1561105D03*
Y1566705D03*
X1072758Y1561105D03*
Y1566705D03*
X1067158Y1561105D03*
Y1566705D03*
X1061558Y1561105D03*
Y1566705D03*
X1055768Y1566675D03*
X1055418Y1560785D03*
X1055618Y1554885D03*
Y1549285D03*
Y1543685D03*
X1078358Y1572305D03*
X1072758D03*
X1067158D03*
X1061558D03*
X1055768Y1572275D03*
Y1577875D03*
X1250500Y273500D03*
X1254000Y722917D03*
X1253900Y1176000D03*
X1378700Y270400D03*
X1378213Y722917D03*
X1378400Y1176000D03*
X1500900Y265600D03*
X1502425Y722917D03*
X1502300Y1176000D03*
X1628000Y270500D03*
X1626638Y722917D03*
X1626000Y1176000D03*
X1750900Y270500D03*
X1753000Y756000D03*
X1747400Y1176000D03*
X1788863Y1017225D03*
X1877400Y265200D03*
X1874807Y707280D03*
X1887000Y1170756D03*
G54D29*
X68037Y209361D03*
Y662017D03*
Y1114773D03*
X142028Y966735D03*
X192249Y209061D03*
X208728Y554735D03*
X191949Y1110473D03*
X316462Y209161D03*
Y661917D03*
Y1114773D03*
X440674Y209161D03*
X440774Y661917D03*
X508274Y1114573D03*
X564987Y209161D03*
Y661917D03*
X564887Y1114673D03*
X689100Y209261D03*
Y662017D03*
X688800Y1110373D03*
X874563Y818831D03*
X873463Y1487165D03*
X1036030Y834829D03*
X1013500Y939000D03*
X1181565Y281343D03*
X1186140Y257688D03*
X1232492Y225125D03*
X1256800Y240661D03*
X1254800Y693417D03*
Y1146173D03*
X1381013Y240661D03*
X1379013Y693417D03*
Y1146173D03*
X1503325Y240561D03*
X1503225Y693417D03*
Y1146173D03*
X1629038Y240561D03*
X1627438Y693417D03*
X1639238Y1146173D03*
X1753850Y240561D03*
X1751650Y1146173D03*
X1783828Y978735D03*
X1859769Y209161D03*
Y661917D03*
X1859991Y1102987D03*
G54D83*
X845670Y5709D03*
X841733D03*
X837795D03*
X833858D03*
X829921D03*
X825984D03*
X822047D03*
X818110D03*
X814173D03*
X810236D03*
X806299D03*
X802362D03*
X845670Y29725D03*
X841733D03*
X837795D03*
X833858D03*
X829921D03*
X825984D03*
X822047D03*
X818110D03*
X814173D03*
X810236D03*
X806299D03*
X802362D03*
X877166Y5709D03*
X873229D03*
X869292D03*
X865355D03*
X861418D03*
X857481D03*
X853544D03*
X849607D03*
X877166Y29725D03*
X873229D03*
X869292D03*
X865355D03*
X861418D03*
X857481D03*
X853544D03*
X849607D03*
G54D74*
X577669Y532781D03*
X563889D03*
Y552881D03*
X577669D03*
X933110Y1519150D03*
Y1539250D03*
X946890Y1519150D03*
Y1539250D03*
X1464090Y539550D03*
X1450310D03*
Y559650D03*
X1464090D03*
G54D56*
X173228Y1114173D03*
X670079D03*
X1343700D03*
X1840551D03*
G54D65*
X445173Y1097726D03*
X454173D03*
X1323500Y188161D03*
Y640917D03*
Y1093673D03*
X1332500Y188161D03*
Y640917D03*
Y1093673D03*
X1447713Y188161D03*
X1456713D03*
X1447713Y640917D03*
X1456713D03*
X1447713Y1093673D03*
X1456713D03*
X1571925Y188161D03*
X1566925Y642917D03*
X1580925Y188161D03*
X1575925Y642917D03*
X1581025Y1087373D03*
X1590025D03*
X1696138Y188161D03*
X1705138D03*
X1696138Y640917D03*
X1705138D03*
X1696138Y1093673D03*
X1705138D03*
X1843417Y187575D03*
X1852417D03*
X1820350Y188161D03*
X1829350D03*
X1843417Y640331D03*
X1852417D03*
X1820350Y640917D03*
X1829350D03*
X1843896Y1092413D03*
X1852896D03*
X1820350Y1093673D03*
X1829350D03*
G54D38*
X72500Y503800D03*
X67500D03*
X72500Y956555D03*
X67500D03*
X126063Y979625D03*
X196712Y503800D03*
X191712D03*
X192763Y567625D03*
X216712Y956355D03*
X221712D03*
X313312Y108831D03*
X320925Y503800D03*
X315925D03*
X320925Y956555D03*
X315925D03*
X445138Y503800D03*
X440138D03*
X445138Y956555D03*
X440138D03*
X539350Y503800D03*
X534350D03*
X520479Y564513D03*
X569350Y956555D03*
X564350D03*
X652663Y511800D03*
X647663D03*
X607460Y556074D03*
X693563Y956555D03*
X688563D03*
X749000Y671800D03*
X865663Y844353D03*
X892700Y1539718D03*
X939000Y1013000D03*
X944776Y940800D03*
X987970Y1013807D03*
X967813Y1548966D03*
X1027063Y860653D03*
X1017000Y1104800D03*
X1064500Y1105800D03*
X1094200Y-42800D03*
X1107100Y1105700D03*
X1269878Y504221D03*
X1264878D03*
X1268742Y956386D03*
X1263742D03*
X1312999Y116925D03*
X1364882Y503800D03*
X1359882D03*
X1367382Y956555D03*
X1362382D03*
X1426419Y522057D03*
X1443700Y525400D03*
X1491594Y503800D03*
X1486594D03*
X1491594Y956555D03*
X1486594D03*
X1615807Y503800D03*
X1610807D03*
X1615807Y956555D03*
X1610807D03*
X1740019Y503800D03*
X1735019D03*
X1740019Y956555D03*
X1735019D03*
X1782666Y956544D03*
X1777666D03*
X1767863Y991625D03*
X1859232Y503800D03*
X1869500Y190544D03*
X1864232Y503800D03*
X1869500Y643300D03*
G54D92*
X942126Y58465D03*
Y346457D03*
Y437598D03*
Y725590D03*
X1110236Y58465D03*
Y346457D03*
Y437598D03*
Y725590D03*
G54D47*
X83237Y247161D03*
Y699917D03*
Y1152673D03*
X130863Y997225D03*
X207449Y247161D03*
X197563Y585225D03*
X207449Y699917D03*
Y1152673D03*
X331662Y247161D03*
Y699917D03*
Y1152673D03*
X455874Y247161D03*
Y699917D03*
X530097Y553231D03*
X580087Y247161D03*
X575329Y506627D03*
X598579Y547831D03*
X580087Y699917D03*
Y1152673D03*
X704300Y247161D03*
Y699917D03*
Y1152673D03*
X874400Y1482760D03*
X957613Y1495424D03*
X967801Y1533926D03*
X1014500Y935000D03*
X1256300Y256161D03*
X1254300Y708917D03*
X1255600Y1161800D03*
X1378513Y708917D03*
X1380513Y256161D03*
X1379800Y1161700D03*
X1502825Y256061D03*
X1502725Y708917D03*
X1504500Y1161700D03*
X1628538Y256061D03*
X1626938Y708917D03*
X1638938Y1161673D03*
X1753350Y256061D03*
X1752500Y1161800D03*
X1772663Y1009225D03*
X1874969Y247161D03*
Y699917D03*
X1876448Y1133143D03*
G54D48*
X77637Y247161D03*
Y699917D03*
Y1152673D03*
X125263Y997225D03*
X201849Y247161D03*
X191963Y585225D03*
X201849Y699917D03*
Y1152673D03*
X326062Y247161D03*
Y699917D03*
Y1152673D03*
X450274Y247161D03*
Y699917D03*
X524497Y553231D03*
X574487Y247161D03*
X569729Y506627D03*
X592979Y547831D03*
X574487Y699917D03*
Y1152673D03*
X698700Y247161D03*
Y699917D03*
Y1152673D03*
X868800Y1482760D03*
X952013Y1495424D03*
X962201Y1533926D03*
X1008900Y935000D03*
X1250700Y256161D03*
X1248700Y708917D03*
X1250000Y1161800D03*
X1374913Y256161D03*
X1372913Y708917D03*
X1374200Y1161700D03*
X1497225Y256061D03*
X1497125Y708917D03*
X1498900Y1161700D03*
X1622938Y256061D03*
X1621338Y708917D03*
X1633338Y1161673D03*
X1747750Y256061D03*
X1746900Y1161800D03*
X1767063Y1009225D03*
X1869369Y247161D03*
Y699917D03*
X1870848Y1133143D03*
G54D39*
X103642Y36220D03*
X173228Y1062992D03*
X421653Y1141732D03*
X654822Y36220D03*
X670079Y1062992D03*
X1274311Y36220D03*
X1343701Y1062992D03*
X1592126Y1141732D03*
X1825492Y36220D03*
X1840551Y1062992D03*
G54D93*
X991713Y-122342D03*
X986713D03*
X981713D03*
X976713D03*
X971713D03*
X966713D03*
X961713D03*
X1036713D03*
X1031713D03*
X1026713D03*
X1021713D03*
X1016713D03*
X1086713D03*
X1081713D03*
X1076713D03*
X1071713D03*
X1066713D03*
X1061713D03*
X1056713D03*
X1051713D03*
X1046713D03*
X1041713D03*
G54D75*
X575700Y533081D03*
X573732D03*
X571763D03*
X569795D03*
X567826D03*
X565858D03*
Y552581D03*
X567826D03*
X569795D03*
X571763D03*
X573732D03*
X575700D03*
X942953Y1519450D03*
X940984D03*
X939016D03*
X937047D03*
X935079D03*
Y1538950D03*
X937047D03*
X939016D03*
X940984D03*
X942953D03*
X944921Y1519450D03*
Y1538950D03*
X1462121Y539850D03*
X1460153D03*
X1458184D03*
X1456216D03*
X1454247D03*
X1452279D03*
Y559350D03*
X1454247D03*
X1456216D03*
X1458184D03*
X1460153D03*
X1462121D03*
G54D66*
X496653Y80906D03*
X1465157D03*
G54D57*
X223100Y920600D03*
X289510Y1342259D03*
X447533Y475900D03*
X458679Y470700D03*
X429613Y1017920D03*
X432657Y1015102D03*
X422373Y1359747D03*
X418922Y1356522D03*
X462133Y473300D03*
X481533Y480875D03*
X536000Y1359826D03*
X541362D03*
X553587Y1346026D03*
X527000Y1340600D03*
X521500Y1342800D03*
X585479Y537731D03*
Y543994D03*
X609334Y538306D03*
Y543306D03*
X658574Y930100D03*
X776400Y956500D03*
X782230Y1323670D03*
X785340Y1320410D03*
X789549Y1322310D03*
X781290Y1328490D03*
X790290Y1328410D03*
X785640Y1328370D03*
X963780Y1022400D03*
X954700Y1524100D03*
Y1530363D03*
X974787Y1525100D03*
Y1529300D03*
X1040180Y437510D03*
X1028657Y1009103D03*
X1079455Y-30742D03*
X1043674Y451921D03*
X1073408Y942399D03*
X1058571Y943852D03*
X1124024Y-30840D03*
X1128765Y-34297D03*
X1111254Y-31020D03*
X1105328Y-31005D03*
X1146768Y-31238D03*
X1139808Y-31171D03*
X1149699Y-35153D03*
X1142293Y-37522D03*
X1215795Y181242D03*
X1324207Y138756D03*
X1315102Y137903D03*
X1316000Y772200D03*
X1312767Y885535D03*
X1375700Y413400D03*
X1347600Y734078D03*
X1344062Y737800D03*
X1354500Y747304D03*
X1360920Y749829D03*
X1334300Y771200D03*
X1338729Y776131D03*
X1338700Y771500D03*
X1373519Y761900D03*
X1369600Y1330100D03*
X1373700Y1330000D03*
X1414882Y397271D03*
X1418225Y421700D03*
X1421239Y558029D03*
Y562229D03*
X1442500Y548400D03*
Y554700D03*
X1474083Y764750D03*
X1471608Y768500D03*
X1500539Y739639D03*
X1498000Y743000D03*
X1489000Y723000D03*
X1476558Y759088D03*
X1479033Y762259D03*
X1486600Y786559D03*
X1494662Y1336000D03*
X1842000Y1344700D03*
G54D84*
X808001Y46220D03*
Y66488D03*
X803167Y631566D03*
Y651834D03*
X808000Y1203666D03*
Y1223934D03*
X1038655Y107235D03*
Y127503D03*
X1126047Y873270D03*
Y893538D03*
X1105647Y914783D03*
Y935051D03*
G54D85*
X853379Y59870D03*
X878179D03*
X1181568Y77168D03*
X1206368D03*
G54D76*
X570779Y542831D03*
X940000Y1529200D03*
X1457200Y549600D03*
G54D94*
X972995Y1165653D03*
X975555D03*
X978115D03*
Y1172153D03*
X972995D03*
X1325735Y65129D03*
X1328295D03*
X1325735Y71629D03*
X1330855Y65129D03*
Y71629D03*
G54D58*
X338971Y64135D03*
X345471Y66695D03*
Y64135D03*
X338971Y69255D03*
X345471D03*
X536871Y547216D03*
Y544656D03*
Y542096D03*
X543371D03*
Y547216D03*
X682452Y112770D03*
Y107650D03*
X675952D03*
Y110210D03*
Y112770D03*
X841508Y1533251D03*
Y1530691D03*
Y1528131D03*
X848008D03*
Y1533251D03*
X907950Y1525060D03*
Y1522500D03*
Y1519940D03*
X914450D03*
Y1525060D03*
X1233900Y230740D03*
Y235860D03*
X1240400D03*
Y233300D03*
Y230740D03*
X1491108Y545215D03*
Y547775D03*
Y550335D03*
X1484608D03*
Y545215D03*
G54D67*
X496653Y110552D03*
X1465157D03*
G54D49*
X111024Y302303D03*
Y755059D03*
Y1207815D03*
X235236Y302303D03*
Y755059D03*
Y1207815D03*
X359449Y302303D03*
Y755059D03*
Y1207815D03*
X483661Y302303D03*
Y755059D03*
Y1207815D03*
X607874Y302303D03*
Y755059D03*
Y1207815D03*
X732087Y302303D03*
Y755059D03*
Y1207815D03*
X1098524Y-115157D03*
X1281693Y302303D03*
Y755059D03*
Y1207815D03*
X1405906Y302303D03*
Y755059D03*
Y1207815D03*
X1530118Y302303D03*
Y755059D03*
Y1207815D03*
X1654331Y302303D03*
Y755059D03*
Y1207815D03*
X1778543Y302303D03*
Y755059D03*
Y1207815D03*
X1902756Y302303D03*
Y755059D03*
Y1207815D03*
G54D86*
X871346Y86000D03*
X860378D03*
X1178334Y726750D03*
X1187784Y47968D03*
X1198752D03*
X1189302Y726750D03*
G54D68*
X503248Y829921D03*
X1673917D03*
G54D59*
X324841Y87515D03*
X327401D03*
X329961D03*
X332521D03*
X335081D03*
X337641D03*
X340201D03*
X342761D03*
X345321D03*
X347881D03*
X350441D03*
X353001D03*
Y109715D03*
X350441D03*
X347881D03*
X345321D03*
X342761D03*
X340201D03*
X337641D03*
X335081D03*
X332521D03*
X329961D03*
X327401D03*
X324841D03*
X876781Y1450061D03*
X879341D03*
X881901D03*
X884461D03*
X887021D03*
X889581D03*
X892141D03*
X894701D03*
Y1472261D03*
X892141D03*
X889581D03*
X887021D03*
X884461D03*
X881901D03*
X879341D03*
X876781D03*
X896420Y921900D03*
X898980D03*
X901540D03*
X904100D03*
X906660D03*
X909220D03*
X911780D03*
X914340D03*
X916900D03*
X919460D03*
X922020D03*
X924580D03*
Y944100D03*
X922020D03*
X919460D03*
X916900D03*
X914340D03*
X911780D03*
X909220D03*
X906660D03*
X904100D03*
X901540D03*
X898980D03*
X896420D03*
X927080Y1013600D03*
X924520D03*
X921960D03*
X919400D03*
X916840D03*
X914280D03*
X911720D03*
X909160D03*
X906600D03*
X904040D03*
X901480D03*
X898920D03*
Y991400D03*
X901480D03*
X904040D03*
X906600D03*
X909160D03*
X911720D03*
X914280D03*
X916840D03*
X919400D03*
X921960D03*
X924520D03*
X927080D03*
X897261Y1450061D03*
X899821D03*
X902381D03*
X904941D03*
Y1472261D03*
X902381D03*
X899821D03*
X897261D03*
X953420Y921900D03*
X955980D03*
X958540D03*
X961100D03*
X963660D03*
X966220D03*
X968780D03*
X971340D03*
X973900D03*
X976460D03*
X979020D03*
X981580D03*
Y944100D03*
X979020D03*
X976460D03*
X973900D03*
X971340D03*
X968780D03*
X966220D03*
X963660D03*
X961100D03*
X958540D03*
X955980D03*
X953420D03*
X948420Y992400D03*
X950980D03*
X953540D03*
X956100D03*
X958660D03*
X961220D03*
X963780D03*
X966340D03*
X968900D03*
X971460D03*
X974020D03*
X976580D03*
Y1014600D03*
X974020D03*
X971460D03*
X968900D03*
X966340D03*
X963780D03*
X961220D03*
X958660D03*
X956100D03*
X953540D03*
X950980D03*
X948420D03*
X1020540Y921400D03*
X1023100D03*
X1025660D03*
X1028220D03*
X1030780D03*
X1033340D03*
X1035900D03*
X1038460D03*
Y943600D03*
X1035900D03*
X1033340D03*
X1030780D03*
X1028220D03*
X1025660D03*
X1023100D03*
X1020540D03*
X997614Y992740D03*
X1000174D03*
X1002734D03*
X1005294D03*
X1007854D03*
X1010414D03*
X1012974D03*
X1015534D03*
X1018094D03*
X1020654D03*
X1023214D03*
X1025774D03*
Y1014940D03*
X1023214D03*
X1020654D03*
X1018094D03*
X1015534D03*
X1012974D03*
X1010414D03*
X1007854D03*
X1005294D03*
X1002734D03*
X1000174D03*
X997614D03*
X1025920Y1083900D03*
X1028480D03*
X1031040D03*
X1033600D03*
X1036160D03*
X1038720D03*
Y1106100D03*
X1036160D03*
X1033600D03*
X1031040D03*
X1028480D03*
X1025920D03*
X1073420Y1084900D03*
X1075980D03*
X1078540D03*
X1081100D03*
X1083660D03*
X1086220D03*
X1041280Y1083900D03*
X1043840D03*
X1046400D03*
X1048960D03*
X1051520D03*
X1054080D03*
X1086220Y1107100D03*
X1083660D03*
X1081100D03*
X1078540D03*
X1075980D03*
X1073420D03*
X1054080Y1106100D03*
X1051520D03*
X1048960D03*
X1046400D03*
X1043840D03*
X1041280D03*
X1088780Y1084900D03*
X1091340D03*
X1093900D03*
X1096460D03*
X1099020D03*
X1101580D03*
X1116420D03*
X1118980D03*
X1121540D03*
X1124100D03*
X1126660D03*
X1129220D03*
X1131780D03*
X1134340D03*
X1101580Y1107100D03*
X1099020D03*
X1096460D03*
X1093900D03*
X1091340D03*
X1088780D03*
X1134340D03*
X1131780D03*
X1129220D03*
X1126660D03*
X1124100D03*
X1121540D03*
X1118980D03*
X1116420D03*
X1136900Y1084900D03*
X1139460D03*
X1142020D03*
X1144580D03*
Y1107100D03*
X1142020D03*
X1139460D03*
X1136900D03*
X1323041Y96135D03*
X1325601D03*
X1328161D03*
Y118335D03*
X1325601D03*
X1323041D03*
X1330721Y96135D03*
X1333281D03*
X1335841D03*
X1338401D03*
X1340961D03*
X1343521D03*
X1346081D03*
X1348641D03*
X1351201D03*
Y118335D03*
X1348641D03*
X1346081D03*
X1343521D03*
X1340961D03*
X1338401D03*
X1335841D03*
X1333281D03*
X1330721D03*
G54D77*
X601418Y516495D03*
X608918Y520370D03*
Y512620D03*
X975023Y1508212D03*
X982523Y1512087D03*
Y1504337D03*
X1005250Y917500D03*
X1012750Y913625D03*
Y921375D03*
G54D95*
X986614Y1619764D03*
X974016D03*
Y1597126D03*
X986614D03*
X974016Y1642401D03*
X986614D03*
X1030709Y1619764D03*
X1014961D03*
X1002362D03*
Y1597126D03*
X1014961D03*
X1030709D03*
X1002362Y1642401D03*
X1014961D03*
X1030709D03*
X1043307Y1619764D03*
Y1597126D03*
Y1642401D03*
G54D87*
X870100Y691616D03*
Y702584D03*
G54D69*
X527145Y564270D03*
X525145Y558670D03*
X529145D03*
X899288Y1539560D03*
X897288Y1533960D03*
X901288D03*
X1100800Y-42800D03*
X1098800Y-48400D03*
X1102800D03*
G54D96*
X974016Y1591220D03*
Y1603031D03*
Y1613858D03*
X986614Y1591220D03*
Y1613858D03*
Y1603031D03*
X974016Y1625669D03*
Y1636496D03*
Y1648307D03*
X986614Y1625669D03*
Y1636496D03*
Y1648307D03*
X1002362Y1591220D03*
Y1603031D03*
Y1613858D03*
X1014961Y1591220D03*
Y1603031D03*
Y1613858D03*
X1030709Y1591220D03*
Y1613858D03*
Y1603031D03*
X1002362Y1625669D03*
Y1636496D03*
Y1648307D03*
X1014961Y1625669D03*
Y1636496D03*
Y1648307D03*
X1030709Y1625669D03*
Y1636496D03*
Y1648307D03*
X1043307Y1591220D03*
Y1603031D03*
Y1613858D03*
Y1625669D03*
Y1636496D03*
Y1648307D03*
X1101457Y1588583D03*
X1119685D03*
X1101457Y1601181D03*
X1119685D03*
G54D78*
X570779Y542831D03*
X940000Y1529200D03*
X1457200Y549600D03*
G54D97*
X1013662Y-103956D03*
X1010512D03*
X1007363D03*
X1004213D03*
X1001063D03*
X997914D03*
X994764D03*
G54D88*
X883763Y829253D03*
X881203D03*
X878643D03*
X876083D03*
Y845553D03*
X878643D03*
X881203D03*
X883763D03*
X1037483Y861953D03*
X1040043D03*
Y845653D03*
X1037483D03*
X1042603Y861953D03*
X1045163D03*
Y845653D03*
X1042603D03*
G54D79*
X648392Y588186D03*
Y593186D03*
Y598186D03*
Y603186D03*
G54D89*
X895676Y1372183D03*
Y1369623D03*
Y1367063D03*
Y1364503D03*
Y1361943D03*
Y1359383D03*
Y1356823D03*
Y1374743D03*
X917876Y1356823D03*
Y1359383D03*
Y1361943D03*
Y1364503D03*
Y1367063D03*
Y1369623D03*
Y1372183D03*
Y1374743D03*
G54D98*
X1017695Y-85425D03*
X1029295D03*
X1040397Y-84867D03*
X1051997D03*
G54D99*
X1032080Y-52355D03*
X1039560D03*
Y-61355D03*
X1035820D03*
X1032080D03*
X1054593Y-57597D03*
X1062073D03*
Y-66597D03*
X1058333D03*
X1054593D03*
M02*
